(kicad_sch
	(version 20250114)
	(generator "eeschema")
	(generator_version "9.0")
	(paper "A3")
	(title_block
		(title "RDIMM DDR5 Tester")
		(date "2026-05-21")
		(rev "2.2.0")
		(company "Antmicro")
		(comment 1 "www.antmicro.com")
		(comment 2 "Antmicro")
	)
	(text "L"
		(exclude_from_sim no)
		(at 163.83 238.76 0)
		(effects
			(font
				(size 1.27 1.27)
			)
			(justify left bottom)
		)
	)
	(text "PWR I^{2}C MUX"
		(exclude_from_sim no)
		(at 15.24 142.24 0)
		(effects
			(font
				(size 2 2)
				(thickness 0.4978)
				(bold yes)
			)
			(justify left bottom)
		)
	)
	(text "L"
		(exclude_from_sim no)
		(at 160.02 241.3 0)
		(effects
			(font
				(size 1.27 1.27)
			)
			(justify left bottom)
		)
	)
	(text "FTDI"
		(exclude_from_sim no)
		(at 157.48 243.84 0)
		(effects
			(font
				(size 1.27 1.27)
			)
			(justify right bottom)
		)
	)
	(text "I3C"
		(exclude_from_sim no)
		(at 175.895 19.685 0)
		(effects
			(font
				(size 3 3)
				(thickness 0.6)
				(bold yes)
			)
			(justify left bottom)
		)
	)
	(text "H"
		(exclude_from_sim no)
		(at 163.83 241.3 0)
		(effects
			(font
				(size 1.27 1.27)
			)
			(justify left bottom)
		)
	)
	(text "H"
		(exclude_from_sim no)
		(at 160.02 243.84 0)
		(effects
			(font
				(size 1.27 1.27)
			)
			(justify left bottom)
		)
	)
	(text "OFF"
		(exclude_from_sim no)
		(at 157.48 236.22 0)
		(effects
			(font
				(size 1.27 1.27)
			)
			(justify right bottom)
		)
	)
	(text "PWR I^{2}C"
		(exclude_from_sim no)
		(at 149.225 233.68 0)
		(effects
			(font
				(size 1.27 1.27)
				(thickness 0.254)
				(bold yes)
			)
			(justify left bottom)
		)
	)
	(text "I^{2}C"
		(exclude_from_sim no)
		(at 15.875 19.685 0)
		(effects
			(font
				(size 3 3)
				(thickness 0.6)
				(bold yes)
			)
			(justify left bottom)
		)
	)
	(text "H"
		(exclude_from_sim no)
		(at 163.83 243.84 0)
		(effects
			(font
				(size 1.27 1.27)
			)
			(justify left bottom)
		)
	)
	(text "0R Mux bypass"
		(exclude_from_sim no)
		(at 283.845 187.325 0)
		(effects
			(font
				(size 1.27 1.27)
			)
			(justify left bottom)
		)
	)
	(text "H"
		(exclude_from_sim no)
		(at 160.02 238.76 0)
		(effects
			(font
				(size 1.27 1.27)
			)
			(justify left bottom)
		)
	)
	(text "IN2"
		(exclude_from_sim no)
		(at 162.56 233.68 0)
		(effects
			(font
				(size 1.27 1.27)
				(thickness 0.254)
				(bold yes)
			)
			(justify left bottom)
		)
	)
	(text "L"
		(exclude_from_sim no)
		(at 160.02 236.22 0)
		(effects
			(font
				(size 1.27 1.27)
			)
			(justify left bottom)
		)
	)
	(text "IN1"
		(exclude_from_sim no)
		(at 158.75 233.68 0)
		(effects
			(font
				(size 1.27 1.27)
				(thickness 0.254)
				(bold yes)
			)
			(justify left bottom)
		)
	)
	(text "L"
		(exclude_from_sim no)
		(at 163.83 236.22 0)
		(effects
			(font
				(size 1.27 1.27)
			)
			(justify left bottom)
		)
	)
	(text "FPGA PWR I^{2}C"
		(exclude_from_sim no)
		(at 157.48 241.3 0)
		(effects
			(font
				(size 1.27 1.27)
			)
			(justify right bottom)
		)
	)
	(text "I3C connector"
		(exclude_from_sim no)
		(at 373.38 95.885 0)
		(effects
			(font
				(size 1.27 1.27)
			)
			(justify left bottom)
		)
	)
	(text "FPGA DDR I^{2}C"
		(exclude_from_sim no)
		(at 157.48 238.76 0)
		(effects
			(font
				(size 1.27 1.27)
			)
			(justify right bottom)
		)
	)
	(junction
		(at 238.76 60.96)
		(diameter 0)
		(color 0 0 0 0)
	)
	(junction
		(at 340.36 85.09)
		(diameter 0)
		(color 0 0 0 0)
	)
	(junction
		(at 275.59 73.66)
		(diameter 0)
		(color 0 0 0 0)
	)
	(junction
		(at 142.24 223.52)
		(diameter 0)
		(color 0 0 0 0)
	)
	(junction
		(at 275.59 81.28)
		(diameter 0)
		(color 0 0 0 0)
	)
	(junction
		(at 367.03 66.04)
		(diameter 0)
		(color 0 0 0 0)
	)
	(junction
		(at 246.38 60.96)
		(diameter 0)
		(color 0 0 0 0)
	)
	(junction
		(at 325.12 60.96)
		(diameter 0)
		(color 0 0 0 0)
	)
	(junction
		(at 269.24 73.66)
		(diameter 0)
		(color 0 0 0 0)
	)
	(junction
		(at 238.76 85.09)
		(diameter 0)
		(color 0 0 0 0)
	)
	(junction
		(at 120.65 189.23)
		(diameter 0)
		(color 0 0 0 0)
	)
	(junction
		(at 123.19 213.36)
		(diameter 0)
		(color 0 0 0 0)
	)
	(junction
		(at 325.12 71.12)
		(diameter 0)
		(color 0 0 0 0)
	)
	(junction
		(at 139.7 196.85)
		(diameter 0)
		(color 0 0 0 0)
	)
	(junction
		(at 120.65 176.53)
		(diameter 0)
		(color 0 0 0 0)
	)
	(junction
		(at 64.77 95.25)
		(diameter 0)
		(color 0 0 0 0)
	)
	(junction
		(at 300.99 199.39)
		(diameter 0)
		(color 0 0 0 0)
	)
	(junction
		(at 369.57 90.17)
		(diameter 0)
		(color 0 0 0 0)
	)
	(junction
		(at 246.38 87.63)
		(diameter 0)
		(color 0 0 0 0)
	)
	(junction
		(at 185.42 186.69)
		(diameter 0)
		(color 0 0 0 0)
	)
	(junction
		(at 185.42 210.82)
		(diameter 0)
		(color 0 0 0 0)
	)
	(junction
		(at 303.53 60.96)
		(diameter 0)
		(color 0 0 0 0)
	)
	(junction
		(at 118.11 81.28)
		(diameter 0)
		(color 0 0 0 0)
	)
	(junction
		(at 300.99 73.66)
		(diameter 0)
		(color 0 0 0 0)
	)
	(junction
		(at 114.3 81.28)
		(diameter 0)
		(color 0 0 0 0)
	)
	(junction
		(at 114.3 95.25)
		(diameter 0)
		(color 0 0 0 0)
	)
	(junction
		(at 68.58 81.28)
		(diameter 0)
		(color 0 0 0 0)
	)
	(junction
		(at 347.98 60.96)
		(diameter 0)
		(color 0 0 0 0)
	)
	(junction
		(at 300.99 208.28)
		(diameter 0)
		(color 0 0 0 0)
	)
	(junction
		(at 222.25 71.12)
		(diameter 0)
		(color 0 0 0 0)
	)
	(junction
		(at 64.77 81.28)
		(diameter 0)
		(color 0 0 0 0)
	)
	(junction
		(at 110.49 97.79)
		(diameter 0)
		(color 0 0 0 0)
	)
	(junction
		(at 123.19 59.69)
		(diameter 0)
		(color 0 0 0 0)
	)
	(junction
		(at 340.36 60.96)
		(diameter 0)
		(color 0 0 0 0)
	)
	(junction
		(at 68.58 97.79)
		(diameter 0)
		(color 0 0 0 0)
	)
	(junction
		(at 297.18 73.66)
		(diameter 0)
		(color 0 0 0 0)
	)
	(junction
		(at 110.49 81.28)
		(diameter 0)
		(color 0 0 0 0)
	)
	(junction
		(at 311.15 60.96)
		(diameter 0)
		(color 0 0 0 0)
	)
	(junction
		(at 347.98 87.63)
		(diameter 0)
		(color 0 0 0 0)
	)
	(junction
		(at 222.25 60.96)
		(diameter 0)
		(color 0 0 0 0)
	)
	(no_connect
		(at 353.06 113.03)
	)
	(bus_entry
		(at 238.76 210.82)
		(size -2.54 -2.54)
		(stroke
			(width 0)
			(type default)
		)
	)
	(bus_entry
		(at 64.77 215.9)
		(size -2.54 -2.54)
		(stroke
			(width 0)
			(type default)
		)
	)
	(bus_entry
		(at 95.25 210.82)
		(size -2.54 -2.54)
		(stroke
			(width 0)
			(type default)
		)
	)
	(bus_entry
		(at 45.72 95.25)
		(size -2.54 -2.54)
		(stroke
			(width 0)
			(type default)
		)
	)
	(bus_entry
		(at 64.77 191.77)
		(size -2.54 -2.54)
		(stroke
			(width 0)
			(type default)
		)
	)
	(bus_entry
		(at 144.78 95.25)
		(size 2.54 -2.54)
		(stroke
			(width 0)
			(type default)
		)
	)
	(bus_entry
		(at 95.25 186.69)
		(size -2.54 -2.54)
		(stroke
			(width 0)
			(type default)
		)
	)
	(bus_entry
		(at 312.42 199.39)
		(size 2.54 -2.54)
		(stroke
			(width 0)
			(type default)
		)
	)
	(bus_entry
		(at 238.76 201.93)
		(size -2.54 -2.54)
		(stroke
			(width 0)
			(type default)
		)
	)
	(bus_entry
		(at 45.72 97.79)
		(size -2.54 -2.54)
		(stroke
			(width 0)
			(type default)
		)
	)
	(bus_entry
		(at 312.42 208.28)
		(size 2.54 -2.54)
		(stroke
			(width 0)
			(type default)
		)
	)
	(bus_entry
		(at 77.47 189.23)
		(size -2.54 -2.54)
		(stroke
			(width 0)
			(type default)
		)
	)
	(bus_entry
		(at 267.97 205.74)
		(size -2.54 -2.54)
		(stroke
			(width 0)
			(type default)
		)
	)
	(bus_entry
		(at 203.2 85.09)
		(size -2.54 -2.54)
		(stroke
			(width 0)
			(type default)
		)
	)
	(bus_entry
		(at 203.2 87.63)
		(size -2.54 -2.54)
		(stroke
			(width 0)
			(type default)
		)
	)
	(bus_entry
		(at 144.78 97.79)
		(size 2.54 -2.54)
		(stroke
			(width 0)
			(type default)
		)
	)
	(bus_entry
		(at 77.47 213.36)
		(size -2.54 -2.54)
		(stroke
			(width 0)
			(type default)
		)
	)
	(bus_entry
		(at 250.19 208.28)
		(size -2.54 -2.54)
		(stroke
			(width 0)
			(type default)
		)
	)
	(bus_entry
		(at 267.97 196.85)
		(size -2.54 -2.54)
		(stroke
			(width 0)
			(type default)
		)
	)
	(bus_entry
		(at 250.19 199.39)
		(size -2.54 -2.54)
		(stroke
			(width 0)
			(type default)
		)
	)
	(wire
		(pts
			(xy 185.42 186.69) (xy 170.18 186.69)
		)
		(stroke
			(width 0)
			(type default)
		)
	)
	(wire
		(pts
			(xy 367.03 82.55) (xy 370.84 82.55)
		)
		(stroke
			(width 0)
			(type default)
		)
	)
	(wire
		(pts
			(xy 120.65 189.23) (xy 143.51 189.23)
		)
		(stroke
			(width 0)
			(type default)
		)
	)
	(bus
		(pts
			(xy 246.38 193.04) (xy 247.65 194.31)
		)
		(stroke
			(width 0)
			(type default)
		)
	)
	(wire
		(pts
			(xy 123.19 176.53) (xy 123.19 177.8)
		)
		(stroke
			(width 0)
			(type default)
		)
	)
	(wire
		(pts
			(xy 381 73.66) (xy 381 72.39)
		)
		(stroke
			(width 0)
			(type default)
		)
	)
	(wire
		(pts
			(xy 74.93 92.71) (xy 78.74 92.71)
		)
		(stroke
			(width 0)
			(type default)
		)
	)
	(wire
		(pts
			(xy 101.6 81.28) (xy 101.6 92.71)
		)
		(stroke
			(width 0)
			(type default)
		)
	)
	(wire
		(pts
			(xy 246.38 60.96) (xy 246.38 71.12)
		)
		(stroke
			(width 0)
			(type default)
		)
	)
	(wire
		(pts
			(xy 250.19 199.39) (xy 287.02 199.39)
		)
		(stroke
			(width 0)
			(type default)
		)
	)
	(bus
		(pts
			(xy 314.96 195.58) (xy 314.96 196.85)
		)
		(stroke
			(width 0)
			(type default)
		)
	)
	(bus
		(pts
			(xy 236.22 199.39) (xy 236.22 208.28)
		)
		(stroke
			(width 0)
			(type default)
		)
	)
	(wire
		(pts
			(xy 185.42 186.69) (xy 185.42 189.23)
		)
		(stroke
			(width 0)
			(type default)
		)
	)
	(wire
		(pts
			(xy 99.06 100.33) (xy 96.52 100.33)
		)
		(stroke
			(width 0)
			(type default)
		)
	)
	(wire
		(pts
			(xy 297.18 81.28) (xy 295.91 81.28)
		)
		(stroke
			(width 0)
			(type default)
		)
	)
	(wire
		(pts
			(xy 300.99 208.28) (xy 300.99 210.82)
		)
		(stroke
			(width 0)
			(type default)
		)
	)
	(wire
		(pts
			(xy 292.1 208.28) (xy 300.99 208.28)
		)
		(stroke
			(width 0)
			(type default)
		)
	)
	(wire
		(pts
			(xy 114.3 81.28) (xy 114.3 85.09)
		)
		(stroke
			(width 0)
			(type default)
		)
	)
	(wire
		(pts
			(xy 340.36 80.01) (xy 340.36 85.09)
		)
		(stroke
			(width 0)
			(type default)
		)
	)
	(wire
		(pts
			(xy 347.98 60.96) (xy 347.98 74.93)
		)
		(stroke
			(width 0)
			(type default)
		)
	)
	(bus
		(pts
			(xy 69.85 184.15) (xy 73.66 184.15)
		)
		(stroke
			(width 0)
			(type default)
		)
	)
	(wire
		(pts
			(xy 139.7 220.98) (xy 143.51 220.98)
		)
		(stroke
			(width 0)
			(type default)
		)
	)
	(polyline
		(pts
			(xy 143.51 233.68) (xy 166.37 233.68)
		)
		(stroke
			(width 0)
			(type solid)
		)
	)
	(wire
		(pts
			(xy 95.25 210.82) (xy 143.51 210.82)
		)
		(stroke
			(width 0)
			(type default)
		)
	)
	(wire
		(pts
			(xy 267.97 205.74) (xy 287.02 205.74)
		)
		(stroke
			(width 0)
			(type default)
		)
	)
	(wire
		(pts
			(xy 269.24 50.8) (xy 269.24 62.23)
		)
		(stroke
			(width 0)
			(type default)
		)
	)
	(wire
		(pts
			(xy 339.09 60.96) (xy 340.36 60.96)
		)
		(stroke
			(width 0)
			(type default)
		)
	)
	(wire
		(pts
			(xy 297.18 60.96) (xy 303.53 60.96)
		)
		(stroke
			(width 0)
			(type default)
		)
	)
	(wire
		(pts
			(xy 68.58 81.28) (xy 68.58 85.09)
		)
		(stroke
			(width 0)
			(type default)
		)
	)
	(wire
		(pts
			(xy 110.49 81.28) (xy 114.3 81.28)
		)
		(stroke
			(width 0)
			(type default)
		)
	)
	(wire
		(pts
			(xy 222.25 60.96) (xy 224.79 60.96)
		)
		(stroke
			(width 0)
			(type default)
		)
	)
	(polyline
		(pts
			(xy 12.7 134.62) (xy 407.67 134.62)
		)
		(stroke
			(width 0)
			(type default)
		)
	)
	(bus
		(pts
			(xy 200.66 81.28) (xy 200.66 82.55)
		)
		(stroke
			(width 0)
			(type default)
		)
	)
	(bus
		(pts
			(xy 151.13 87.63) (xy 148.59 87.63)
		)
		(stroke
			(width 0)
			(type default)
		)
	)
	(polyline
		(pts
			(xy 143.51 231.14) (xy 166.37 231.14)
		)
		(stroke
			(width 0)
			(type default)
		)
	)
	(wire
		(pts
			(xy 214.63 60.96) (xy 222.25 60.96)
		)
		(stroke
			(width 0)
			(type default)
		)
	)
	(wire
		(pts
			(xy 250.19 208.28) (xy 287.02 208.28)
		)
		(stroke
			(width 0)
			(type default)
		)
	)
	(polyline
		(pts
			(xy 172.72 12.7) (xy 172.72 134.62)
		)
		(stroke
			(width 0)
			(type default)
		)
	)
	(wire
		(pts
			(xy 311.15 60.96) (xy 325.12 60.96)
		)
		(stroke
			(width 0)
			(type default)
		)
	)
	(wire
		(pts
			(xy 74.93 81.28) (xy 68.58 81.28)
		)
		(stroke
			(width 0)
			(type default)
		)
	)
	(bus
		(pts
			(xy 92.71 184.15) (xy 92.71 208.28)
		)
		(stroke
			(width 0)
			(type default)
		)
	)
	(wire
		(pts
			(xy 123.19 59.69) (xy 123.19 57.15)
		)
		(stroke
			(width 0)
			(type default)
		)
	)
	(wire
		(pts
			(xy 269.24 73.66) (xy 275.59 73.66)
		)
		(stroke
			(width 0)
			(type default)
		)
	)
	(wire
		(pts
			(xy 170.18 213.36) (xy 180.34 213.36)
		)
		(stroke
			(width 0)
			(type default)
		)
	)
	(bus
		(pts
			(xy 62.23 187.96) (xy 62.23 189.23)
		)
		(stroke
			(width 0)
			(type default)
		)
	)
	(wire
		(pts
			(xy 64.77 90.17) (xy 64.77 95.25)
		)
		(stroke
			(width 0)
			(type default)
		)
	)
	(wire
		(pts
			(xy 347.98 60.96) (xy 340.36 60.96)
		)
		(stroke
			(width 0)
			(type default)
		)
	)
	(wire
		(pts
			(xy 347.98 87.63) (xy 370.84 87.63)
		)
		(stroke
			(width 0)
			(type default)
		)
	)
	(wire
		(pts
			(xy 114.3 95.25) (xy 144.78 95.25)
		)
		(stroke
			(width 0)
			(type default)
		)
	)
	(wire
		(pts
			(xy 110.49 97.79) (xy 144.78 97.79)
		)
		(stroke
			(width 0)
			(type default)
		)
	)
	(wire
		(pts
			(xy 300.99 196.85) (xy 292.1 196.85)
		)
		(stroke
			(width 0)
			(type default)
		)
	)
	(wire
		(pts
			(xy 49.53 50.8) (xy 49.53 53.34)
		)
		(stroke
			(width 0)
			(type default)
		)
	)
	(wire
		(pts
			(xy 110.49 90.17) (xy 110.49 97.79)
		)
		(stroke
			(width 0)
			(type default)
		)
	)
	(wire
		(pts
			(xy 275.59 91.44) (xy 278.13 91.44)
		)
		(stroke
			(width 0)
			(type default)
		)
	)
	(bus
		(pts
			(xy 74.93 185.42) (xy 74.93 186.69)
		)
		(stroke
			(width 0)
			(type default)
		)
	)
	(wire
		(pts
			(xy 350.52 115.57) (xy 350.52 116.84)
		)
		(stroke
			(width 0)
			(type default)
		)
	)
	(wire
		(pts
			(xy 300.99 199.39) (xy 300.99 196.85)
		)
		(stroke
			(width 0)
			(type default)
		)
	)
	(wire
		(pts
			(xy 170.18 199.39) (xy 171.45 199.39)
		)
		(stroke
			(width 0)
			(type default)
		)
	)
	(wire
		(pts
			(xy 356.87 60.96) (xy 356.87 63.5)
		)
		(stroke
			(width 0)
			(type default)
		)
	)
	(bus
		(pts
			(xy 74.93 186.69) (xy 74.93 210.82)
		)
		(stroke
			(width 0)
			(type default)
		)
	)
	(wire
		(pts
			(xy 99.06 100.33) (xy 99.06 101.6)
		)
		(stroke
			(width 0)
			(type default)
		)
	)
	(wire
		(pts
			(xy 120.65 176.53) (xy 123.19 176.53)
		)
		(stroke
			(width 0)
			(type default)
		)
	)
	(wire
		(pts
			(xy 129.54 50.8) (xy 129.54 52.07)
		)
		(stroke
			(width 0)
			(type default)
		)
	)
	(wire
		(pts
			(xy 350.52 115.57) (xy 353.06 115.57)
		)
		(stroke
			(width 0)
			(type default)
		)
	)
	(wire
		(pts
			(xy 300.99 199.39) (xy 312.42 199.39)
		)
		(stroke
			(width 0)
			(type default)
		)
	)
	(wire
		(pts
			(xy 367.03 58.42) (xy 367.03 66.04)
		)
		(stroke
			(width 0)
			(type default)
		)
	)
	(wire
		(pts
			(xy 323.85 71.12) (xy 325.12 71.12)
		)
		(stroke
			(width 0)
			(type default)
		)
	)
	(wire
		(pts
			(xy 256.54 60.96) (xy 256.54 63.5)
		)
		(stroke
			(width 0)
			(type default)
		)
	)
	(bus
		(pts
			(xy 91.44 181.61) (xy 92.71 182.88)
		)
		(stroke
			(width 0)
			(type default)
		)
	)
	(wire
		(pts
			(xy 340.36 85.09) (xy 370.84 85.09)
		)
		(stroke
			(width 0)
			(type default)
		)
	)
	(wire
		(pts
			(xy 311.15 57.15) (xy 311.15 60.96)
		)
		(stroke
			(width 0)
			(type default)
		)
	)
	(wire
		(pts
			(xy 222.25 68.58) (xy 222.25 71.12)
		)
		(stroke
			(width 0)
			(type default)
		)
	)
	(bus
		(pts
			(xy 247.65 196.85) (xy 247.65 205.74)
		)
		(stroke
			(width 0)
			(type default)
		)
	)
	(wire
		(pts
			(xy 303.53 50.8) (xy 303.53 52.07)
		)
		(stroke
			(width 0)
			(type default)
		)
	)
	(bus
		(pts
			(xy 200.66 81.28) (xy 199.39 80.01)
		)
		(stroke
			(width 0)
			(type default)
		)
	)
	(wire
		(pts
			(xy 295.91 85.09) (xy 340.36 85.09)
		)
		(stroke
			(width 0)
			(type default)
		)
	)
	(bus
		(pts
			(xy 234.95 195.58) (xy 236.22 196.85)
		)
		(stroke
			(width 0)
			(type default)
		)
	)
	(wire
		(pts
			(xy 64.77 81.28) (xy 64.77 85.09)
		)
		(stroke
			(width 0)
			(type default)
		)
	)
	(wire
		(pts
			(xy 77.47 213.36) (xy 123.19 213.36)
		)
		(stroke
			(width 0)
			(type default)
		)
	)
	(wire
		(pts
			(xy 118.11 80.01) (xy 118.11 81.28)
		)
		(stroke
			(width 0)
			(type default)
		)
	)
	(wire
		(pts
			(xy 303.53 57.15) (xy 303.53 60.96)
		)
		(stroke
			(width 0)
			(type default)
		)
	)
	(bus
		(pts
			(xy 60.96 186.69) (xy 62.23 187.96)
		)
		(stroke
			(width 0)
			(type default)
		)
	)
	(wire
		(pts
			(xy 275.59 73.66) (xy 275.59 81.28)
		)
		(stroke
			(width 0)
			(type default)
		)
	)
	(polyline
		(pts
			(xy 166.37 243.84) (xy 143.51 243.84)
		)
		(stroke
			(width 0)
			(type default)
		)
	)
	(wire
		(pts
			(xy 331.47 110.49) (xy 353.06 110.49)
		)
		(stroke
			(width 0)
			(type default)
		)
	)
	(wire
		(pts
			(xy 238.76 201.93) (xy 287.02 201.93)
		)
		(stroke
			(width 0)
			(type default)
		)
	)
	(wire
		(pts
			(xy 185.42 210.82) (xy 170.18 210.82)
		)
		(stroke
			(width 0)
			(type default)
		)
	)
	(wire
		(pts
			(xy 331.47 107.95) (xy 353.06 107.95)
		)
		(stroke
			(width 0)
			(type default)
		)
	)
	(wire
		(pts
			(xy 298.45 91.44) (xy 298.45 92.71)
		)
		(stroke
			(width 0)
			(type default)
		)
	)
	(wire
		(pts
			(xy 303.53 60.96) (xy 311.15 60.96)
		)
		(stroke
			(width 0)
			(type default)
		)
	)
	(wire
		(pts
			(xy 123.19 59.69) (xy 129.54 59.69)
		)
		(stroke
			(width 0)
			(type default)
		)
	)
	(bus
		(pts
			(xy 92.71 182.88) (xy 92.71 184.15)
		)
		(stroke
			(width 0)
			(type default)
		)
	)
	(wire
		(pts
			(xy 203.2 85.09) (xy 238.76 85.09)
		)
		(stroke
			(width 0)
			(type default)
		)
	)
	(wire
		(pts
			(xy 139.7 196.85) (xy 139.7 220.98)
		)
		(stroke
			(width 0)
			(type default)
		)
	)
	(wire
		(pts
			(xy 45.72 95.25) (xy 64.77 95.25)
		)
		(stroke
			(width 0)
			(type default)
		)
	)
	(bus
		(pts
			(xy 236.22 196.85) (xy 236.22 199.39)
		)
		(stroke
			(width 0)
			(type default)
		)
	)
	(wire
		(pts
			(xy 123.19 50.8) (xy 123.19 52.07)
		)
		(stroke
			(width 0)
			(type default)
		)
	)
	(wire
		(pts
			(xy 275.59 72.39) (xy 275.59 73.66)
		)
		(stroke
			(width 0)
			(type default)
		)
	)
	(bus
		(pts
			(xy 318.77 194.31) (xy 316.23 194.31)
		)
		(stroke
			(width 0)
			(type default)
		)
	)
	(bus
		(pts
			(xy 265.43 194.31) (xy 265.43 203.2)
		)
		(stroke
			(width 0)
			(type default)
		)
	)
	(wire
		(pts
			(xy 370.84 90.17) (xy 369.57 90.17)
		)
		(stroke
			(width 0)
			(type default)
		)
	)
	(wire
		(pts
			(xy 68.58 97.79) (xy 78.74 97.79)
		)
		(stroke
			(width 0)
			(type default)
		)
	)
	(wire
		(pts
			(xy 171.45 223.52) (xy 171.45 224.79)
		)
		(stroke
			(width 0)
			(type default)
		)
	)
	(wire
		(pts
			(xy 101.6 81.28) (xy 110.49 81.28)
		)
		(stroke
			(width 0)
			(type default)
		)
	)
	(wire
		(pts
			(xy 297.18 81.28) (xy 297.18 73.66)
		)
		(stroke
			(width 0)
			(type default)
		)
	)
	(wire
		(pts
			(xy 96.52 92.71) (xy 101.6 92.71)
		)
		(stroke
			(width 0)
			(type default)
		)
	)
	(bus
		(pts
			(xy 196.85 80.01) (xy 199.39 80.01)
		)
		(stroke
			(width 0)
			(type default)
		)
	)
	(wire
		(pts
			(xy 62.23 50.8) (xy 62.23 53.34)
		)
		(stroke
			(width 0)
			(type default)
		)
	)
	(wire
		(pts
			(xy 222.25 71.12) (xy 228.6 71.12)
		)
		(stroke
			(width 0)
			(type default)
		)
	)
	(wire
		(pts
			(xy 370.84 80.01) (xy 369.57 80.01)
		)
		(stroke
			(width 0)
			(type default)
		)
	)
	(bus
		(pts
			(xy 200.66 82.55) (xy 200.66 85.09)
		)
		(stroke
			(width 0)
			(type default)
		)
	)
	(wire
		(pts
			(xy 298.45 91.44) (xy 295.91 91.44)
		)
		(stroke
			(width 0)
			(type default)
		)
	)
	(bus
		(pts
			(xy 62.23 189.23) (xy 62.23 213.36)
		)
		(stroke
			(width 0)
			(type default)
		)
	)
	(wire
		(pts
			(xy 123.19 182.88) (xy 123.19 213.36)
		)
		(stroke
			(width 0)
			(type default)
		)
	)
	(wire
		(pts
			(xy 120.65 175.26) (xy 120.65 176.53)
		)
		(stroke
			(width 0)
			(type default)
		)
	)
	(wire
		(pts
			(xy 246.38 60.96) (xy 256.54 60.96)
		)
		(stroke
			(width 0)
			(type default)
		)
	)
	(wire
		(pts
			(xy 330.2 68.58) (xy 330.2 71.12)
		)
		(stroke
			(width 0)
			(type default)
		)
	)
	(wire
		(pts
			(xy 367.03 66.04) (xy 367.03 82.55)
		)
		(stroke
			(width 0)
			(type default)
		)
	)
	(wire
		(pts
			(xy 238.76 60.96) (xy 246.38 60.96)
		)
		(stroke
			(width 0)
			(type default)
		)
	)
	(wire
		(pts
			(xy 170.18 223.52) (xy 171.45 223.52)
		)
		(stroke
			(width 0)
			(type default)
		)
	)
	(polyline
		(pts
			(xy 162.56 231.14) (xy 162.56 243.84)
		)
		(stroke
			(width 0)
			(type default)
		)
	)
	(wire
		(pts
			(xy 300.99 208.28) (xy 312.42 208.28)
		)
		(stroke
			(width 0)
			(type default)
		)
	)
	(bus
		(pts
			(xy 90.17 181.61) (xy 91.44 181.61)
		)
		(stroke
			(width 0)
			(type default)
		)
	)
	(wire
		(pts
			(xy 64.77 95.25) (xy 78.74 95.25)
		)
		(stroke
			(width 0)
			(type default)
		)
	)
	(wire
		(pts
			(xy 347.98 80.01) (xy 347.98 87.63)
		)
		(stroke
			(width 0)
			(type default)
		)
	)
	(wire
		(pts
			(xy 238.76 60.96) (xy 237.49 60.96)
		)
		(stroke
			(width 0)
			(type default)
		)
	)
	(wire
		(pts
			(xy 77.47 189.23) (xy 120.65 189.23)
		)
		(stroke
			(width 0)
			(type default)
		)
	)
	(wire
		(pts
			(xy 185.42 185.42) (xy 185.42 186.69)
		)
		(stroke
			(width 0)
			(type default)
		)
	)
	(polyline
		(pts
			(xy 143.51 231.14) (xy 143.51 243.84)
		)
		(stroke
			(width 0)
			(type default)
		)
	)
	(wire
		(pts
			(xy 222.25 60.96) (xy 222.25 63.5)
		)
		(stroke
			(width 0)
			(type default)
		)
	)
	(wire
		(pts
			(xy 300.99 201.93) (xy 292.1 201.93)
		)
		(stroke
			(width 0)
			(type default)
		)
	)
	(wire
		(pts
			(xy 238.76 76.2) (xy 238.76 85.09)
		)
		(stroke
			(width 0)
			(type default)
		)
	)
	(wire
		(pts
			(xy 369.57 80.01) (xy 369.57 90.17)
		)
		(stroke
			(width 0)
			(type default)
		)
	)
	(bus
		(pts
			(xy 147.32 92.71) (xy 147.32 95.25)
		)
		(stroke
			(width 0)
			(type default)
		)
	)
	(wire
		(pts
			(xy 297.18 60.96) (xy 297.18 73.66)
		)
		(stroke
			(width 0)
			(type default)
		)
	)
	(wire
		(pts
			(xy 64.77 81.28) (xy 68.58 81.28)
		)
		(stroke
			(width 0)
			(type default)
		)
	)
	(wire
		(pts
			(xy 114.3 90.17) (xy 114.3 95.25)
		)
		(stroke
			(width 0)
			(type default)
		)
	)
	(wire
		(pts
			(xy 325.12 71.12) (xy 325.12 68.58)
		)
		(stroke
			(width 0)
			(type default)
		)
	)
	(polyline
		(pts
			(xy 166.37 231.14) (xy 166.37 243.84)
		)
		(stroke
			(width 0)
			(type default)
		)
	)
	(wire
		(pts
			(xy 381 66.04) (xy 367.03 66.04)
		)
		(stroke
			(width 0)
			(type default)
		)
	)
	(wire
		(pts
			(xy 344.17 105.41) (xy 353.06 105.41)
		)
		(stroke
			(width 0)
			(type default)
		)
	)
	(bus
		(pts
			(xy 43.18 91.44) (xy 43.18 92.71)
		)
		(stroke
			(width 0)
			(type default)
		)
	)
	(wire
		(pts
			(xy 381 67.31) (xy 381 66.04)
		)
		(stroke
			(width 0)
			(type default)
		)
	)
	(bus
		(pts
			(xy 41.91 90.17) (xy 43.18 91.44)
		)
		(stroke
			(width 0)
			(type default)
		)
	)
	(bus
		(pts
			(xy 316.23 194.31) (xy 314.96 195.58)
		)
		(stroke
			(width 0)
			(type default)
		)
	)
	(wire
		(pts
			(xy 246.38 76.2) (xy 246.38 87.63)
		)
		(stroke
			(width 0)
			(type default)
		)
	)
	(wire
		(pts
			(xy 120.65 176.53) (xy 120.65 177.8)
		)
		(stroke
			(width 0)
			(type default)
		)
	)
	(bus
		(pts
			(xy 58.42 186.69) (xy 60.96 186.69)
		)
		(stroke
			(width 0)
			(type default)
		)
	)
	(wire
		(pts
			(xy 45.72 97.79) (xy 68.58 97.79)
		)
		(stroke
			(width 0)
			(type default)
		)
	)
	(wire
		(pts
			(xy 325.12 60.96) (xy 325.12 63.5)
		)
		(stroke
			(width 0)
			(type default)
		)
	)
	(wire
		(pts
			(xy 269.24 67.31) (xy 269.24 73.66)
		)
		(stroke
			(width 0)
			(type default)
		)
	)
	(wire
		(pts
			(xy 275.59 81.28) (xy 275.59 91.44)
		)
		(stroke
			(width 0)
			(type default)
		)
	)
	(wire
		(pts
			(xy 267.97 196.85) (xy 287.02 196.85)
		)
		(stroke
			(width 0)
			(type default)
		)
	)
	(wire
		(pts
			(xy 64.77 78.74) (xy 64.77 81.28)
		)
		(stroke
			(width 0)
			(type default)
		)
	)
	(wire
		(pts
			(xy 347.98 60.96) (xy 356.87 60.96)
		)
		(stroke
			(width 0)
			(type default)
		)
	)
	(bus
		(pts
			(xy 243.84 193.04) (xy 246.38 193.04)
		)
		(stroke
			(width 0)
			(type default)
		)
	)
	(wire
		(pts
			(xy 185.42 209.55) (xy 185.42 210.82)
		)
		(stroke
			(width 0)
			(type default)
		)
	)
	(wire
		(pts
			(xy 325.12 71.12) (xy 330.2 71.12)
		)
		(stroke
			(width 0)
			(type default)
		)
	)
	(bus
		(pts
			(xy 232.41 195.58) (xy 234.95 195.58)
		)
		(stroke
			(width 0)
			(type default)
		)
	)
	(wire
		(pts
			(xy 300.99 73.66) (xy 300.99 74.93)
		)
		(stroke
			(width 0)
			(type default)
		)
	)
	(wire
		(pts
			(xy 295.91 87.63) (xy 347.98 87.63)
		)
		(stroke
			(width 0)
			(type default)
		)
	)
	(polyline
		(pts
			(xy 143.51 238.76) (xy 166.37 238.76)
		)
		(stroke
			(width 0)
			(type default)
		)
	)
	(wire
		(pts
			(xy 238.76 210.82) (xy 287.02 210.82)
		)
		(stroke
			(width 0)
			(type default)
		)
	)
	(wire
		(pts
			(xy 203.2 87.63) (xy 246.38 87.63)
		)
		(stroke
			(width 0)
			(type default)
		)
	)
	(wire
		(pts
			(xy 185.42 210.82) (xy 185.42 213.36)
		)
		(stroke
			(width 0)
			(type default)
		)
	)
	(wire
		(pts
			(xy 143.51 199.39) (xy 142.24 199.39)
		)
		(stroke
			(width 0)
			(type default)
		)
	)
	(wire
		(pts
			(xy 185.42 218.44) (xy 185.42 220.98)
		)
		(stroke
			(width 0)
			(type default)
		)
	)
	(wire
		(pts
			(xy 60.96 50.8) (xy 62.23 50.8)
		)
		(stroke
			(width 0)
			(type default)
		)
	)
	(wire
		(pts
			(xy 180.34 189.23) (xy 170.18 189.23)
		)
		(stroke
			(width 0)
			(type default)
		)
	)
	(wire
		(pts
			(xy 185.42 194.31) (xy 185.42 196.85)
		)
		(stroke
			(width 0)
			(type default)
		)
	)
	(wire
		(pts
			(xy 367.03 50.8) (xy 367.03 53.34)
		)
		(stroke
			(width 0)
			(type default)
		)
	)
	(wire
		(pts
			(xy 142.24 199.39) (xy 142.24 223.52)
		)
		(stroke
			(width 0)
			(type default)
		)
	)
	(bus
		(pts
			(xy 247.65 194.31) (xy 247.65 196.85)
		)
		(stroke
			(width 0)
			(type default)
		)
	)
	(wire
		(pts
			(xy 300.99 210.82) (xy 292.1 210.82)
		)
		(stroke
			(width 0)
			(type default)
		)
	)
	(wire
		(pts
			(xy 275.59 81.28) (xy 278.13 81.28)
		)
		(stroke
			(width 0)
			(type default)
		)
	)
	(wire
		(pts
			(xy 238.76 85.09) (xy 278.13 85.09)
		)
		(stroke
			(width 0)
			(type default)
		)
	)
	(wire
		(pts
			(xy 95.25 186.69) (xy 143.51 186.69)
		)
		(stroke
			(width 0)
			(type default)
		)
	)
	(wire
		(pts
			(xy 228.6 71.12) (xy 228.6 68.58)
		)
		(stroke
			(width 0)
			(type default)
		)
	)
	(wire
		(pts
			(xy 311.15 50.8) (xy 311.15 52.07)
		)
		(stroke
			(width 0)
			(type default)
		)
	)
	(wire
		(pts
			(xy 96.52 95.25) (xy 114.3 95.25)
		)
		(stroke
			(width 0)
			(type default)
		)
	)
	(wire
		(pts
			(xy 325.12 60.96) (xy 326.39 60.96)
		)
		(stroke
			(width 0)
			(type default)
		)
	)
	(wire
		(pts
			(xy 171.45 199.39) (xy 171.45 200.66)
		)
		(stroke
			(width 0)
			(type default)
		)
	)
	(wire
		(pts
			(xy 137.16 223.52) (xy 142.24 223.52)
		)
		(stroke
			(width 0)
			(type default)
		)
	)
	(bus
		(pts
			(xy 265.43 191.77) (xy 265.43 194.31)
		)
		(stroke
			(width 0)
			(type default)
		)
	)
	(wire
		(pts
			(xy 118.11 81.28) (xy 123.19 81.28)
		)
		(stroke
			(width 0)
			(type default)
		)
	)
	(bus
		(pts
			(xy 73.66 184.15) (xy 74.93 185.42)
		)
		(stroke
			(width 0)
			(type default)
		)
	)
	(wire
		(pts
			(xy 123.19 213.36) (xy 143.51 213.36)
		)
		(stroke
			(width 0)
			(type default)
		)
	)
	(wire
		(pts
			(xy 369.57 90.17) (xy 369.57 91.44)
		)
		(stroke
			(width 0)
			(type default)
		)
	)
	(wire
		(pts
			(xy 238.76 60.96) (xy 238.76 71.12)
		)
		(stroke
			(width 0)
			(type default)
		)
	)
	(bus
		(pts
			(xy 43.18 92.71) (xy 43.18 95.25)
		)
		(stroke
			(width 0)
			(type default)
		)
	)
	(wire
		(pts
			(xy 344.17 102.87) (xy 344.17 105.41)
		)
		(stroke
			(width 0)
			(type default)
		)
	)
	(wire
		(pts
			(xy 292.1 199.39) (xy 300.99 199.39)
		)
		(stroke
			(width 0)
			(type default)
		)
	)
	(wire
		(pts
			(xy 96.52 97.79) (xy 110.49 97.79)
		)
		(stroke
			(width 0)
			(type default)
		)
	)
	(wire
		(pts
			(xy 214.63 50.8) (xy 214.63 60.96)
		)
		(stroke
			(width 0)
			(type default)
		)
	)
	(wire
		(pts
			(xy 142.24 223.52) (xy 143.51 223.52)
		)
		(stroke
			(width 0)
			(type default)
		)
	)
	(wire
		(pts
			(xy 64.77 191.77) (xy 143.51 191.77)
		)
		(stroke
			(width 0)
			(type default)
		)
	)
	(wire
		(pts
			(xy 74.93 81.28) (xy 74.93 92.71)
		)
		(stroke
			(width 0)
			(type default)
		)
	)
	(polyline
		(pts
			(xy 158.75 231.14) (xy 158.75 243.84)
		)
		(stroke
			(width 0)
			(type solid)
		)
	)
	(wire
		(pts
			(xy 297.18 73.66) (xy 300.99 73.66)
		)
		(stroke
			(width 0)
			(type default)
		)
	)
	(bus
		(pts
			(xy 147.32 88.9) (xy 147.32 92.71)
		)
		(stroke
			(width 0)
			(type default)
		)
	)
	(wire
		(pts
			(xy 114.3 81.28) (xy 118.11 81.28)
		)
		(stroke
			(width 0)
			(type default)
		)
	)
	(bus
		(pts
			(xy 264.16 190.5) (xy 265.43 191.77)
		)
		(stroke
			(width 0)
			(type default)
		)
	)
	(wire
		(pts
			(xy 120.65 182.88) (xy 120.65 189.23)
		)
		(stroke
			(width 0)
			(type default)
		)
	)
	(wire
		(pts
			(xy 110.49 81.28) (xy 110.49 85.09)
		)
		(stroke
			(width 0)
			(type default)
		)
	)
	(bus
		(pts
			(xy 314.96 196.85) (xy 314.96 205.74)
		)
		(stroke
			(width 0)
			(type default)
		)
	)
	(wire
		(pts
			(xy 300.99 72.39) (xy 300.99 73.66)
		)
		(stroke
			(width 0)
			(type default)
		)
	)
	(wire
		(pts
			(xy 300.99 199.39) (xy 300.99 201.93)
		)
		(stroke
			(width 0)
			(type default)
		)
	)
	(wire
		(pts
			(xy 300.99 205.74) (xy 292.1 205.74)
		)
		(stroke
			(width 0)
			(type default)
		)
	)
	(wire
		(pts
			(xy 300.99 205.74) (xy 300.99 208.28)
		)
		(stroke
			(width 0)
			(type default)
		)
	)
	(polyline
		(pts
			(xy 143.51 236.22) (xy 166.37 236.22)
		)
		(stroke
			(width 0)
			(type default)
		)
	)
	(polyline
		(pts
			(xy 143.51 241.3) (xy 166.37 241.3)
		)
		(stroke
			(width 0)
			(type default)
		)
	)
	(wire
		(pts
			(xy 129.54 59.69) (xy 129.54 57.15)
		)
		(stroke
			(width 0)
			(type default)
		)
	)
	(wire
		(pts
			(xy 340.36 60.96) (xy 340.36 74.93)
		)
		(stroke
			(width 0)
			(type default)
		)
	)
	(wire
		(pts
			(xy 119.38 59.69) (xy 123.19 59.69)
		)
		(stroke
			(width 0)
			(type default)
		)
	)
	(wire
		(pts
			(xy 269.24 73.66) (xy 269.24 74.93)
		)
		(stroke
			(width 0)
			(type default)
		)
	)
	(wire
		(pts
			(xy 76.2 100.33) (xy 78.74 100.33)
		)
		(stroke
			(width 0)
			(type default)
		)
	)
	(wire
		(pts
			(xy 68.58 90.17) (xy 68.58 97.79)
		)
		(stroke
			(width 0)
			(type default)
		)
	)
	(bus
		(pts
			(xy 261.62 190.5) (xy 264.16 190.5)
		)
		(stroke
			(width 0)
			(type default)
		)
	)
	(wire
		(pts
			(xy 64.77 215.9) (xy 143.51 215.9)
		)
		(stroke
			(width 0)
			(type default)
		)
	)
	(bus
		(pts
			(xy 40.64 90.17) (xy 41.91 90.17)
		)
		(stroke
			(width 0)
			(type default)
		)
	)
	(bus
		(pts
			(xy 147.32 88.9) (xy 148.59 87.63)
		)
		(stroke
			(width 0)
			(type default)
		)
	)
	(wire
		(pts
			(xy 212.09 71.12) (xy 222.25 71.12)
		)
		(stroke
			(width 0)
			(type default)
		)
	)
	(wire
		(pts
			(xy 137.16 196.85) (xy 139.7 196.85)
		)
		(stroke
			(width 0)
			(type default)
		)
	)
	(wire
		(pts
			(xy 143.51 196.85) (xy 139.7 196.85)
		)
		(stroke
			(width 0)
			(type default)
		)
	)
	(wire
		(pts
			(xy 246.38 87.63) (xy 278.13 87.63)
		)
		(stroke
			(width 0)
			(type default)
		)
	)
	(label "FPGA_DDR.SCL"
		(at 45.72 95.25 0)
		(effects
			(font
				(size 1.27 1.27)
			)
			(justify left bottom)
		)
	)
	(label "PWR.SCL"
		(at 180.34 213.36 180)
		(effects
			(font
				(size 1.27 1.27)
			)
			(justify right bottom)
		)
	)
	(label "FPGA_DDR.SCL"
		(at 267.97 205.74 0)
		(effects
			(font
				(size 1.27 1.27)
			)
			(justify left bottom)
		)
	)
	(label "FTDI.SDA"
		(at 64.77 191.77 0)
		(effects
			(font
				(size 1.27 1.27)
			)
			(justify left bottom)
		)
	)
	(label "DDR.SDA"
		(at 144.78 97.79 180)
		(effects
			(font
				(size 1.27 1.27)
			)
			(justify right bottom)
		)
	)
	(label "I3C_EXT.SDA"
		(at 363.22 87.63 180)
		(effects
			(font
				(size 1.27 1.27)
			)
			(justify right bottom)
		)
	)
	(label "PWR.SDA"
		(at 180.34 189.23 180)
		(effects
			(font
				(size 1.27 1.27)
			)
			(justify right bottom)
		)
	)
	(label "PWR.SDA"
		(at 311.15 199.39 180)
		(effects
			(font
				(size 1.27 1.27)
			)
			(justify right bottom)
		)
	)
	(label "FPGA_DDR.SDA"
		(at 267.97 196.85 0)
		(effects
			(font
				(size 1.27 1.27)
			)
			(justify left bottom)
		)
	)
	(label "FPGA_I3C.SDA"
		(at 203.2 87.63 0)
		(effects
			(font
				(size 1.27 1.27)
			)
			(justify left bottom)
		)
	)
	(label "FTDI.SCL"
		(at 238.76 210.82 0)
		(effects
			(font
				(size 1.27 1.27)
			)
			(justify left bottom)
		)
	)
	(label "DDR.SCL"
		(at 144.78 95.25 180)
		(effects
			(font
				(size 1.27 1.27)
			)
			(justify right bottom)
		)
	)
	(label "FPGA_DDR.SDA"
		(at 45.72 97.79 0)
		(effects
			(font
				(size 1.27 1.27)
			)
			(justify left bottom)
		)
	)
	(label "FPGA_I3C.SCL"
		(at 203.2 85.09 0)
		(effects
			(font
				(size 1.27 1.27)
			)
			(justify left bottom)
		)
	)
	(label "FPGA_PWR.SDA"
		(at 77.47 189.23 0)
		(effects
			(font
				(size 1.27 1.27)
			)
			(justify left bottom)
		)
	)
	(label "FTDI.SCL"
		(at 64.77 215.9 0)
		(effects
			(font
				(size 1.27 1.27)
			)
			(justify left bottom)
		)
	)
	(label "I3C_EXT.SCL"
		(at 331.47 110.49 0)
		(effects
			(font
				(size 1.27 1.27)
			)
			(justify left bottom)
		)
	)
	(label "FPGA_PWR.SCL"
		(at 250.19 208.28 0)
		(effects
			(font
				(size 1.27 1.27)
			)
			(justify left bottom)
		)
	)
	(label "FPGA_PWR.SCL"
		(at 77.47 213.36 0)
		(effects
			(font
				(size 1.27 1.27)
			)
			(justify left bottom)
		)
	)
	(label "FPGA_PWR.SDA"
		(at 250.19 199.39 0)
		(effects
			(font
				(size 1.27 1.27)
			)
			(justify left bottom)
		)
	)
	(label "FTDI.SDA"
		(at 238.76 201.93 0)
		(effects
			(font
				(size 1.27 1.27)
			)
			(justify left bottom)
		)
	)
	(label "PWR.SCL"
		(at 312.42 208.28 180)
		(effects
			(font
				(size 1.27 1.27)
			)
			(justify right bottom)
		)
	)
	(label "I3C_EXT.SDA"
		(at 331.47 107.95 0)
		(effects
			(font
				(size 1.27 1.27)
			)
			(justify left bottom)
		)
	)
	(label "FPGA_DDR.SCL"
		(at 95.25 210.82 0)
		(effects
			(font
				(size 1.27 1.27)
			)
			(justify left bottom)
		)
	)
	(label "I3C_EXT.SCL"
		(at 363.22 85.09 180)
		(effects
			(font
				(size 1.27 1.27)
			)
			(justify right bottom)
		)
	)
	(label "FPGA_DDR.SDA"
		(at 95.25 186.69 0)
		(effects
			(font
				(size 1.27 1.27)
			)
			(justify left bottom)
		)
	)
	(global_label "IN1"
		(shape input)
		(at 137.16 196.85 180)
		(fields_autoplaced yes)
		(effects
			(font
				(size 1.27 1.27)
			)
			(justify right)
		)
		(property "Intersheetrefs" "${INTERSHEET_REFS}"
			(at 131.691 196.9294 0)
			(effects
				(font
					(size 1.27 1.27)
				)
				(justify right)
			)
		)
	)
	(global_label "~{I3C_EXT_PU}"
		(shape input)
		(at 323.85 71.12 180)
		(fields_autoplaced yes)
		(effects
			(font
				(size 1.27 1.27)
			)
			(justify right)
		)
		(property "Intersheetrefs" "${INTERSHEET_REFS}"
			(at 310.5729 71.12 0)
			(effects
				(font
					(size 1.27 1.27)
				)
				(justify right)
			)
		)
	)
	(global_label "VDDSPD"
		(shape input)
		(at 119.38 59.69 180)
		(fields_autoplaced yes)
		(effects
			(font
				(size 1.27 1.27)
			)
			(justify right)
		)
		(property "Intersheetrefs" "${INTERSHEET_REFS}"
			(at 109.6709 59.69 0)
			(effects
				(font
					(size 1.27 1.27)
				)
				(justify right)
			)
		)
	)
	(global_label "IN2"
		(shape input)
		(at 137.16 223.52 180)
		(fields_autoplaced yes)
		(effects
			(font
				(size 1.27 1.27)
			)
			(justify right)
		)
		(property "Intersheetrefs" "${INTERSHEET_REFS}"
			(at 131.691 223.5994 0)
			(effects
				(font
					(size 1.27 1.27)
				)
				(justify right)
			)
		)
	)
	(global_label "VDDSPD"
		(shape input)
		(at 123.19 81.28 0)
		(fields_autoplaced yes)
		(effects
			(font
				(size 1.27 1.27)
			)
			(justify left)
		)
		(property "Intersheetrefs" "${INTERSHEET_REFS}"
			(at 132.8991 81.28 0)
			(effects
				(font
					(size 1.27 1.27)
				)
				(justify left)
			)
		)
	)
	(global_label "VDDSPD"
		(shape input)
		(at 60.96 50.8 180)
		(fields_autoplaced yes)
		(effects
			(font
				(size 1.27 1.27)
			)
			(justify right)
		)
		(property "Intersheetrefs" "${INTERSHEET_REFS}"
			(at 51.2509 50.8 0)
			(effects
				(font
					(size 1.27 1.27)
				)
				(justify right)
			)
		)
	)
	(global_label "~{FPGA_I3C_EXT_PU}"
		(shape input)
		(at 212.09 71.12 180)
		(fields_autoplaced yes)
		(effects
			(font
				(size 1.27 1.27)
			)
			(justify right)
		)
		(property "Intersheetrefs" "${INTERSHEET_REFS}"
			(at 193.1281 71.12 0)
			(effects
				(font
					(size 1.27 1.27)
				)
				(justify right)
			)
		)
	)
	(hierarchical_label "FPGA_DDR{I^{2}C}"
		(shape bidirectional)
		(at 40.64 90.17 180)
		(effects
			(font
				(size 1.27 1.27)
			)
			(justify right)
		)
	)
	(hierarchical_label "PWR{I^{2}C}"
		(shape bidirectional)
		(at 318.77 194.31 0)
		(effects
			(font
				(size 1.27 1.27)
			)
			(justify left)
		)
	)
	(hierarchical_label "DDR{I^{2}C}"
		(shape bidirectional)
		(at 151.13 87.63 0)
		(effects
			(font
				(size 1.27 1.27)
			)
			(justify left)
		)
	)
	(hierarchical_label "FTDI{I^{2}C}"
		(shape bidirectional)
		(at 232.41 195.58 180)
		(effects
			(font
				(size 1.27 1.27)
			)
			(justify right)
		)
	)
	(hierarchical_label "FPGA_DDR{I^{2}C}"
		(shape bidirectional)
		(at 90.17 181.61 180)
		(effects
			(font
				(size 1.27 1.27)
			)
			(justify right)
		)
	)
	(hierarchical_label "FPGA_PWR{I^{2}C}"
		(shape bidirectional)
		(at 69.85 184.15 180)
		(effects
			(font
				(size 1.27 1.27)
			)
			(justify right)
		)
	)
	(hierarchical_label "FTDI{I^{2}C}"
		(shape bidirectional)
		(at 58.42 186.69 180)
		(effects
			(font
				(size 1.27 1.27)
			)
			(justify right)
		)
	)
	(hierarchical_label "FPGA_DDR{I^{2}C}"
		(shape bidirectional)
		(at 261.62 190.5 180)
		(effects
			(font
				(size 1.27 1.27)
			)
			(justify right)
		)
	)
	(hierarchical_label "FPGA_PWR{I^{2}C}"
		(shape bidirectional)
		(at 243.84 193.04 180)
		(effects
			(font
				(size 1.27 1.27)
			)
			(justify right)
		)
	)
	(hierarchical_label "FPGA_I3C{I^{2}C}"
		(shape bidirectional)
		(at 196.85 80.01 180)
		(effects
			(font
				(size 1.27 1.27)
			)
			(justify right)
		)
	)
	(symbol
		(lib_id "antmicroResistors0402:R_4k7_0402")
		(at 114.3 85.09 270)
		(unit 1)
		(exclude_from_sim no)
		(in_bom yes)
		(on_board yes)
		(dnp no)
		(property "Reference" "R125"
			(at 115.57 86.36 90)
			(effects
				(font
					(size 1.27 1.27)
				)
				(justify left)
			)
		)
		(property "Value" "R_4k7_0402"
			(at 101.6 105.41 0)
			(effects
				(font
					(size 1.27 1.27)
					(thickness 0.15)
				)
				(justify left bottom)
				(hide yes)
			)
		)
		(property "Footprint" "antmicro-footprints:R_0402_1005Metric"
			(at 99.06 105.41 0)
			(effects
				(font
					(size 1.27 1.27)
					(thickness 0.15)
				)
				(justify left bottom)
				(hide yes)
			)
		)
		(property "Datasheet" "https://www.bourns.com/docs/product-datasheets/cr.pdf"
			(at 96.52 105.41 0)
			(effects
				(font
					(size 1.27 1.27)
					(thickness 0.15)
				)
				(justify left bottom)
				(hide yes)
			)
		)
		(property "Description" ""
			(at 114.3 85.09 0)
			(effects
				(font
					(size 1.27 1.27)
				)
				(hide yes)
			)
		)
		(property "Manufacturer" "Bourns"
			(at 91.44 105.41 0)
			(effects
				(font
					(size 1.27 1.27)
					(thickness 0.15)
				)
				(justify left bottom)
				(hide yes)
			)
		)
		(property "MPN" "CR0402-FX-4701GLF"
			(at 93.98 105.41 0)
			(effects
				(font
					(size 1.27 1.27)
					(thickness 0.15)
				)
				(justify left bottom)
				(hide yes)
			)
		)
		(property "Val" "4k7"
			(at 115.57 88.9 90)
			(effects
				(font
					(size 1.27 1.27)
					(thickness 0.15)
				)
				(justify left)
			)
		)
		(property "License" "Apache-2.0"
			(at 88.9 105.41 0)
			(effects
				(font
					(size 1.27 1.27)
					(thickness 0.15)
				)
				(justify left bottom)
				(hide yes)
			)
		)
		(property "Author" "Antmicro"
			(at 86.36 105.41 0)
			(effects
				(font
					(size 1.27 1.27)
					(thickness 0.15)
				)
				(justify left bottom)
				(hide yes)
			)
		)
		(property "Tolerance" "1%"
			(at 104.14 105.41 0)
			(effects
				(font
					(size 1.27 1.27)
				)
				(justify left bottom)
				(hide yes)
			)
		)
		(pin "1"
		)
		(pin "2"
		)
		(instances
			(project "data-center-rdimm-ddr5-tester"
				(path ""
					(reference "R125")
					(unit 1)
				)
			)
		)
	)
	(symbol
		(lib_id "antmicroTestPoints:TP_1mm_SMD")
		(at 76.2 100.33 180)
		(unit 1)
		(exclude_from_sim no)
		(in_bom no)
		(on_board yes)
		(dnp no)
		(fields_autoplaced yes)
		(property "Reference" "TP7"
			(at 71.12 100.33 0)
			(effects
				(font
					(size 1.27 1.27)
				)
				(justify left)
			)
		)
		(property "Value" "TP_1mm_SMD"
			(at 60.96 92.71 0)
			(effects
				(font
					(size 1.27 1.27)
					(thickness 0.15)
				)
				(justify left bottom)
				(hide yes)
			)
		)
		(property "Footprint" "antmicro-footprints:TP_SMD_1mm"
			(at 60.96 90.17 0)
			(effects
				(font
					(size 1.27 1.27)
					(thickness 0.15)
				)
				(justify left bottom)
				(hide yes)
			)
		)
		(property "Datasheet" ""
			(at 60.96 87.63 0)
			(effects
				(font
					(size 1.27 1.27)
					(thickness 0.15)
				)
				(justify left bottom)
				(hide yes)
			)
		)
		(property "Description" ""
			(at 76.2 100.33 0)
			(effects
				(font
					(size 1.27 1.27)
				)
				(hide yes)
			)
		)
		(property "MPN" ""
			(at 76.2 100.33 0)
			(effects
				(font
					(size 1.27 1.27)
				)
				(hide yes)
			)
		)
		(property "Manufacturer" ""
			(at 76.2 100.33 0)
			(effects
				(font
					(size 1.27 1.27)
				)
				(hide yes)
			)
		)
		(property "Author" "Antmicro"
			(at 60.96 85.09 0)
			(effects
				(font
					(size 1.27 1.27)
					(thickness 0.15)
				)
				(justify left bottom)
				(hide yes)
			)
		)
		(property "License" "Apache-2.0"
			(at 60.96 82.55 0)
			(effects
				(font
					(size 1.27 1.27)
					(thickness 0.15)
				)
				(justify left bottom)
				(hide yes)
			)
		)
		(pin "1"
		)
		(instances
			(project "data-center-rdimm-ddr5-tester"
				(path ""
					(reference "TP7")
					(unit 1)
				)
			)
		)
	)
	(symbol
		(lib_id "antmicropower:+3V3")
		(at 269.24 50.8 0)
		(unit 1)
		(exclude_from_sim no)
		(in_bom yes)
		(on_board yes)
		(dnp no)
		(property "Reference" "#PWR0506"
			(at 284.48 50.8 0)
			(effects
				(font
					(size 1.27 1.27)
					(thickness 0.15)
				)
				(justify left bottom)
				(hide yes)
			)
		)
		(property "Value" "+3V3"
			(at 269.24 46.99 0)
			(effects
				(font
					(size 1.27 1.27)
					(thickness 0.15)
				)
			)
		)
		(property "Footprint" ""
			(at 284.48 58.42 0)
			(effects
				(font
					(size 1.27 1.27)
					(thickness 0.15)
				)
				(justify left bottom)
				(hide yes)
			)
		)
		(property "Datasheet" ""
			(at 284.48 60.96 0)
			(effects
				(font
					(size 1.27 1.27)
					(thickness 0.15)
				)
				(justify left bottom)
				(hide yes)
			)
		)
		(property "Description" ""
			(at 269.24 50.8 0)
			(effects
				(font
					(size 1.27 1.27)
				)
				(hide yes)
			)
		)
		(property "Author" "Antmicro"
			(at 284.48 53.34 0)
			(effects
				(font
					(size 1.27 1.27)
					(thickness 0.15)
				)
				(justify left bottom)
				(hide yes)
			)
		)
		(property "License" "Apache-2.0"
			(at 284.48 55.88 0)
			(effects
				(font
					(size 1.27 1.27)
					(thickness 0.15)
				)
				(justify left bottom)
				(hide yes)
			)
		)
		(pin "1"
		)
		(instances
			(project "data-center-rdimm-ddr5-tester"
				(path ""
					(reference "#PWR0506")
					(unit 1)
				)
			)
		)
	)
	(symbol
		(lib_id "antmicroCapacitors0402:C_100n_0402")
		(at 62.23 53.34 90)
		(mirror x)
		(unit 1)
		(exclude_from_sim no)
		(in_bom yes)
		(on_board yes)
		(dnp no)
		(fields_autoplaced yes)
		(property "Reference" "C166"
			(at 64.5541 55.0557 90)
			(effects
				(font
					(size 1.27 1.27)
				)
				(justify right)
			)
		)
		(property "Value" "C_100n_0402"
			(at 72.39 73.66 0)
			(effects
				(font
					(size 1.27 1.27)
					(thickness 0.15)
				)
				(justify left bottom)
				(hide yes)
			)
		)
		(property "Footprint" "antmicro-footprints:C_0402_1005Metric"
			(at 74.93 73.66 0)
			(effects
				(font
					(size 1.27 1.27)
					(thickness 0.15)
				)
				(justify left bottom)
				(hide yes)
			)
		)
		(property "Datasheet" "https://www.murata.com/products/productdetail?partno=GRM155R61H104KE14%23"
			(at 77.47 73.66 0)
			(effects
				(font
					(size 1.27 1.27)
					(thickness 0.15)
				)
				(justify left bottom)
				(hide yes)
			)
		)
		(property "Description" ""
			(at 62.23 53.34 0)
			(effects
				(font
					(size 1.27 1.27)
				)
				(hide yes)
			)
		)
		(property "Manufacturer" "Murata"
			(at 82.55 73.66 0)
			(effects
				(font
					(size 1.27 1.27)
					(thickness 0.15)
				)
				(justify left bottom)
				(hide yes)
			)
		)
		(property "MPN" "GRM155R61H104KE14D"
			(at 80.01 73.66 0)
			(effects
				(font
					(size 1.27 1.27)
					(thickness 0.15)
				)
				(justify left bottom)
				(hide yes)
			)
		)
		(property "Val" "100n"
			(at 64.5541 57.586 90)
			(effects
				(font
					(size 1.27 1.27)
					(thickness 0.15)
				)
				(justify right)
			)
		)
		(property "License" "Apache-2.0"
			(at 85.09 73.66 0)
			(effects
				(font
					(size 1.27 1.27)
					(thickness 0.15)
				)
				(justify left bottom)
				(hide yes)
			)
		)
		(property "Author" "Antmicro"
			(at 87.63 73.66 0)
			(effects
				(font
					(size 1.27 1.27)
					(thickness 0.15)
				)
				(justify left bottom)
				(hide yes)
			)
		)
		(property "Voltage" "50V"
			(at 90.17 73.66 0)
			(effects
				(font
					(size 1.27 1.27)
				)
				(justify left bottom)
				(hide yes)
			)
		)
		(property "Dielectric" "X5R"
			(at 92.71 73.66 0)
			(effects
				(font
					(size 1.27 1.27)
				)
				(justify left bottom)
				(hide yes)
			)
		)
		(pin "1"
		)
		(pin "2"
		)
		(instances
			(project "data-center-rdimm-ddr5-tester"
				(path ""
					(reference "C166")
					(unit 1)
				)
			)
		)
	)
	(symbol
		(lib_id "antmicroResistors0402:R_4k7_0402")
		(at 340.36 80.01 90)
		(unit 1)
		(exclude_from_sim no)
		(in_bom yes)
		(on_board yes)
		(dnp no)
		(property "Reference" "R241"
			(at 341.63 76.2 90)
			(effects
				(font
					(size 1.27 1.27)
					(thickness 0.15)
				)
				(justify right)
			)
		)
		(property "Value" "R_4k7_0402"
			(at 353.06 59.69 0)
			(effects
				(font
					(size 1.27 1.27)
					(thickness 0.15)
				)
				(justify left bottom)
				(hide yes)
			)
		)
		(property "Footprint" "antmicro-footprints:R_0402_1005Metric"
			(at 355.6 59.69 0)
			(effects
				(font
					(size 1.27 1.27)
					(thickness 0.15)
				)
				(justify left bottom)
				(hide yes)
			)
		)
		(property "Datasheet" "https://www.bourns.com/docs/product-datasheets/cr.pdf"
			(at 358.14 59.69 0)
			(effects
				(font
					(size 1.27 1.27)
					(thickness 0.15)
				)
				(justify left bottom)
				(hide yes)
			)
		)
		(property "Description" ""
			(at 340.36 80.01 0)
			(effects
				(font
					(size 1.27 1.27)
				)
				(hide yes)
			)
		)
		(property "MPN" "CR0402-FX-4701GLF"
			(at 360.68 59.69 0)
			(effects
				(font
					(size 1.27 1.27)
					(thickness 0.15)
				)
				(justify left bottom)
				(hide yes)
			)
		)
		(property "Manufacturer" "Bourns"
			(at 363.22 59.69 0)
			(effects
				(font
					(size 1.27 1.27)
					(thickness 0.15)
				)
				(justify left bottom)
				(hide yes)
			)
		)
		(property "License" "Apache-2.0"
			(at 365.76 59.69 0)
			(effects
				(font
					(size 1.27 1.27)
					(thickness 0.15)
				)
				(justify left bottom)
				(hide yes)
			)
		)
		(property "Author" "Antmicro"
			(at 368.3 59.69 0)
			(effects
				(font
					(size 1.27 1.27)
					(thickness 0.15)
				)
				(justify left bottom)
				(hide yes)
			)
		)
		(property "Val" "4k7"
			(at 341.63 78.74 90)
			(effects
				(font
					(size 1.27 1.27)
					(thickness 0.15)
				)
				(justify right)
			)
		)
		(property "Tolerance" "1%"
			(at 350.52 59.69 0)
			(effects
				(font
					(size 1.27 1.27)
				)
				(justify left bottom)
				(hide yes)
			)
		)
		(pin "2"
		)
		(pin "1"
		)
		(instances
			(project "data-center-rdimm-ddr5-tester"
				(path ""
					(reference "R241")
					(unit 1)
				)
			)
		)
	)
	(symbol
		(lib_id "antmicroResistors0402:R_0R_0402")
		(at 292.1 208.28 180)
		(unit 1)
		(exclude_from_sim no)
		(in_bom no)
		(on_board yes)
		(dnp yes)
		(property "Reference" "R178"
			(at 291.465 207.01 0)
			(effects
				(font
					(size 1.27 1.27)
				)
				(justify right)
			)
		)
		(property "Value" "R_0R_0402"
			(at 271.78 195.58 0)
			(effects
				(font
					(size 1.27 1.27)
					(thickness 0.15)
				)
				(justify left bottom)
				(hide yes)
			)
		)
		(property "Footprint" "antmicro-footprints:R_0402_1005Metric"
			(at 271.78 193.04 0)
			(effects
				(font
					(size 1.27 1.27)
					(thickness 0.15)
				)
				(justify left bottom)
				(hide yes)
			)
		)
		(property "Datasheet" "https://industrial.panasonic.com/cdbs/www-data/pdf/RDA0000/AOA0000C301.pdf"
			(at 271.78 190.5 0)
			(effects
				(font
					(size 1.27 1.27)
					(thickness 0.15)
				)
				(justify left bottom)
				(hide yes)
			)
		)
		(property "Description" ""
			(at 292.1 208.28 0)
			(effects
				(font
					(size 1.27 1.27)
				)
				(hide yes)
			)
		)
		(property "Manufacturer" "Panasonic"
			(at 271.78 185.42 0)
			(effects
				(font
					(size 1.27 1.27)
					(thickness 0.15)
				)
				(justify left bottom)
				(hide yes)
			)
		)
		(property "MPN" "ERJ2GE0R00X"
			(at 271.78 187.96 0)
			(effects
				(font
					(size 1.27 1.27)
					(thickness 0.15)
				)
				(justify left bottom)
				(hide yes)
			)
		)
		(property "Val" "0R"
			(at 284.48 207.01 0)
			(effects
				(font
					(size 1.27 1.27)
					(thickness 0.15)
				)
				(justify right)
			)
		)
		(property "License" "Apache-2.0"
			(at 271.78 182.88 0)
			(effects
				(font
					(size 1.27 1.27)
					(thickness 0.15)
				)
				(justify left bottom)
				(hide yes)
			)
		)
		(property "Author" "Antmicro"
			(at 271.78 180.34 0)
			(effects
				(font
					(size 1.27 1.27)
					(thickness 0.15)
				)
				(justify left bottom)
				(hide yes)
			)
		)
		(property "Tolerance" "~"
			(at 271.78 198.12 0)
			(effects
				(font
					(size 1.27 1.27)
				)
				(justify left bottom)
				(hide yes)
			)
		)
		(property "Current" "1A"
			(at 293.3699 205.74 90)
			(effects
				(font
					(size 1.27 1.27)
					(thickness 0.15)
				)
				(justify right)
				(hide yes)
			)
		)
		(pin "1"
		)
		(pin "2"
		)
		(instances
			(project "data-center-rdimm-ddr5-tester"
				(path ""
					(reference "R178")
					(unit 1)
				)
			)
		)
	)
	(symbol
		(lib_id "antmicroLogicTranslatorsLevelShifters:TCA39306_VSSOP")
		(at 295.91 81.28 0)
		(mirror y)
		(unit 1)
		(exclude_from_sim no)
		(in_bom yes)
		(on_board yes)
		(dnp no)
		(property "Reference" "U49"
			(at 287.02 74.93 0)
			(effects
				(font
					(size 1.27 1.27)
					(thickness 0.15)
				)
			)
		)
		(property "Value" "TCA39306_VSSOP"
			(at 264.16 83.82 0)
			(effects
				(font
					(size 1.27 1.27)
					(thickness 0.15)
				)
				(justify left bottom)
				(hide yes)
			)
		)
		(property "Footprint" "antmicro-footprints:VSSOP-8_2.3x2mm_P0.5mm"
			(at 264.16 86.36 0)
			(effects
				(font
					(size 1.27 1.27)
					(thickness 0.15)
				)
				(justify left bottom)
				(hide yes)
			)
		)
		(property "Datasheet" "https://www.ti.com/lit/ds/symlink/tca39306.pdf?ts=1630428611843&ref_url=https%253A%252F%252Fwww.ti.com%252Fproduct%252FTCA39306"
			(at 264.16 88.9 0)
			(effects
				(font
					(size 1.27 1.27)
					(thickness 0.15)
				)
				(justify left bottom)
				(hide yes)
			)
		)
		(property "Description" ""
			(at 295.91 81.28 0)
			(effects
				(font
					(size 1.27 1.27)
				)
				(hide yes)
			)
		)
		(property "MPN" "TCA39306DCUR"
			(at 287.02 77.47 0)
			(effects
				(font
					(size 1.27 1.27)
					(thickness 0.15)
				)
			)
		)
		(property "Manufacturer" "Texas Instruments"
			(at 264.16 93.98 0)
			(effects
				(font
					(size 1.27 1.27)
					(thickness 0.15)
				)
				(justify left bottom)
				(hide yes)
			)
		)
		(property "Author" "Antmicro"
			(at 264.16 96.52 0)
			(effects
				(font
					(size 1.27 1.27)
					(thickness 0.15)
				)
				(justify left bottom)
				(hide yes)
			)
		)
		(property "License" "Apache-2.0"
			(at 264.16 99.06 0)
			(effects
				(font
					(size 1.27 1.27)
					(thickness 0.15)
				)
				(justify left bottom)
				(hide yes)
			)
		)
		(pin "6"
		)
		(pin "7"
		)
		(pin "5"
		)
		(pin "1"
		)
		(pin "8"
		)
		(pin "4"
		)
		(pin "3"
		)
		(pin "2"
		)
		(instances
			(project "data-center-rdimm-ddr5-tester"
				(path ""
					(reference "U49")
					(unit 1)
				)
			)
		)
	)
	(symbol
		(lib_id "antmicroResistors0402:R_4k7_0402")
		(at 120.65 177.8 270)
		(unit 1)
		(exclude_from_sim no)
		(in_bom yes)
		(on_board yes)
		(dnp no)
		(property "Reference" "R150"
			(at 119.38 179.07 90)
			(effects
				(font
					(size 1.27 1.27)
				)
				(justify right)
			)
		)
		(property "Value" "R_4k7_0402"
			(at 107.95 198.12 0)
			(effects
				(font
					(size 1.27 1.27)
					(thickness 0.15)
				)
				(justify left bottom)
				(hide yes)
			)
		)
		(property "Footprint" "antmicro-footprints:R_0402_1005Metric"
			(at 105.41 198.12 0)
			(effects
				(font
					(size 1.27 1.27)
					(thickness 0.15)
				)
				(justify left bottom)
				(hide yes)
			)
		)
		(property "Datasheet" "https://www.bourns.com/docs/product-datasheets/cr.pdf"
			(at 102.87 198.12 0)
			(effects
				(font
					(size 1.27 1.27)
					(thickness 0.15)
				)
				(justify left bottom)
				(hide yes)
			)
		)
		(property "Description" ""
			(at 120.65 177.8 0)
			(effects
				(font
					(size 1.27 1.27)
				)
				(hide yes)
			)
		)
		(property "Manufacturer" "Bourns"
			(at 97.79 198.12 0)
			(effects
				(font
					(size 1.27 1.27)
					(thickness 0.15)
				)
				(justify left bottom)
				(hide yes)
			)
		)
		(property "MPN" "CR0402-FX-4701GLF"
			(at 100.33 198.12 0)
			(effects
				(font
					(size 1.27 1.27)
					(thickness 0.15)
				)
				(justify left bottom)
				(hide yes)
			)
		)
		(property "Val" "4k7"
			(at 119.38 182.245 90)
			(effects
				(font
					(size 1.27 1.27)
					(thickness 0.15)
				)
				(justify right)
			)
		)
		(property "License" "Apache-2.0"
			(at 95.25 198.12 0)
			(effects
				(font
					(size 1.27 1.27)
					(thickness 0.15)
				)
				(justify left bottom)
				(hide yes)
			)
		)
		(property "Author" "Antmicro"
			(at 92.71 198.12 0)
			(effects
				(font
					(size 1.27 1.27)
					(thickness 0.15)
				)
				(justify left bottom)
				(hide yes)
			)
		)
		(property "Tolerance" "1%"
			(at 110.49 198.12 0)
			(effects
				(font
					(size 1.27 1.27)
				)
				(justify left bottom)
				(hide yes)
			)
		)
		(pin "1"
		)
		(pin "2"
		)
		(instances
			(project "data-center-rdimm-ddr5-tester"
				(path ""
					(reference "R150")
					(unit 1)
				)
			)
		)
	)
	(symbol
		(lib_id "antmicroResistors0402:R_4k7_0402")
		(at 110.49 85.09 270)
		(unit 1)
		(exclude_from_sim no)
		(in_bom yes)
		(on_board yes)
		(dnp no)
		(property "Reference" "R124"
			(at 109.22 86.36 90)
			(effects
				(font
					(size 1.27 1.27)
				)
				(justify right)
			)
		)
		(property "Value" "R_4k7_0402"
			(at 97.79 105.41 0)
			(effects
				(font
					(size 1.27 1.27)
					(thickness 0.15)
				)
				(justify left bottom)
				(hide yes)
			)
		)
		(property "Footprint" "antmicro-footprints:R_0402_1005Metric"
			(at 95.25 105.41 0)
			(effects
				(font
					(size 1.27 1.27)
					(thickness 0.15)
				)
				(justify left bottom)
				(hide yes)
			)
		)
		(property "Datasheet" "https://www.bourns.com/docs/product-datasheets/cr.pdf"
			(at 92.71 105.41 0)
			(effects
				(font
					(size 1.27 1.27)
					(thickness 0.15)
				)
				(justify left bottom)
				(hide yes)
			)
		)
		(property "Description" ""
			(at 110.49 85.09 0)
			(effects
				(font
					(size 1.27 1.27)
				)
				(hide yes)
			)
		)
		(property "Manufacturer" "Bourns"
			(at 87.63 105.41 0)
			(effects
				(font
					(size 1.27 1.27)
					(thickness 0.15)
				)
				(justify left bottom)
				(hide yes)
			)
		)
		(property "MPN" "CR0402-FX-4701GLF"
			(at 90.17 105.41 0)
			(effects
				(font
					(size 1.27 1.27)
					(thickness 0.15)
				)
				(justify left bottom)
				(hide yes)
			)
		)
		(property "Val" "4k7"
			(at 109.22 88.9 90)
			(effects
				(font
					(size 1.27 1.27)
					(thickness 0.15)
				)
				(justify right)
			)
		)
		(property "License" "Apache-2.0"
			(at 85.09 105.41 0)
			(effects
				(font
					(size 1.27 1.27)
					(thickness 0.15)
				)
				(justify left bottom)
				(hide yes)
			)
		)
		(property "Author" "Antmicro"
			(at 82.55 105.41 0)
			(effects
				(font
					(size 1.27 1.27)
					(thickness 0.15)
				)
				(justify left bottom)
				(hide yes)
			)
		)
		(property "Tolerance" "1%"
			(at 100.33 105.41 0)
			(effects
				(font
					(size 1.27 1.27)
				)
				(justify left bottom)
				(hide yes)
			)
		)
		(pin "1"
		)
		(pin "2"
		)
		(instances
			(project "data-center-rdimm-ddr5-tester"
				(path ""
					(reference "R124")
					(unit 1)
				)
			)
		)
	)
	(symbol
		(lib_id "antmicroInterfaceAnalogSwitchesMultiplexersDemultiplexers:TS5A3359_VSSOP")
		(at 143.51 210.82 0)
		(unit 1)
		(exclude_from_sim no)
		(in_bom yes)
		(on_board yes)
		(dnp no)
		(fields_autoplaced yes)
		(property "Reference" "U24"
			(at 156.845 203.2 0)
			(effects
				(font
					(size 1.27 1.27)
					(thickness 0.15)
				)
			)
		)
		(property "Value" "TS5A3359_VSSOP"
			(at 185.42 215.9 0)
			(effects
				(font
					(size 1.27 1.27)
					(thickness 0.15)
				)
				(justify left bottom)
				(hide yes)
			)
		)
		(property "Footprint" "antmicro-footprints:VSSOP-8_2.3x2mm_P0.5mm"
			(at 185.42 218.44 0)
			(effects
				(font
					(size 1.27 1.27)
					(thickness 0.15)
				)
				(justify left bottom)
				(hide yes)
			)
		)
		(property "Datasheet" "https://www.ti.com/general/docs/suppproductinfo.tsp?distId=26&gotoUrl=http%3A%2F%2Fwww.ti.com%2Flit%2Fgpn%2Fts5a3359"
			(at 185.42 220.98 0)
			(effects
				(font
					(size 1.27 1.27)
					(thickness 0.15)
				)
				(justify left bottom)
				(hide yes)
			)
		)
		(property "Description" ""
			(at 143.51 210.82 0)
			(effects
				(font
					(size 1.27 1.27)
				)
				(hide yes)
			)
		)
		(property "MPN" "TS5A3359DCUR"
			(at 156.845 205.74 0)
			(effects
				(font
					(size 1.27 1.27)
					(thickness 0.15)
				)
			)
		)
		(property "Manufacturer" "Texas Instruments"
			(at 185.42 226.06 0)
			(effects
				(font
					(size 1.27 1.27)
					(thickness 0.15)
				)
				(justify left bottom)
				(hide yes)
			)
		)
		(property "Author" "Antmicro"
			(at 185.42 228.6 0)
			(effects
				(font
					(size 1.27 1.27)
					(thickness 0.15)
				)
				(justify left bottom)
				(hide yes)
			)
		)
		(property "License" "Apache-2.0"
			(at 185.42 231.14 0)
			(effects
				(font
					(size 1.27 1.27)
					(thickness 0.15)
				)
				(justify left bottom)
				(hide yes)
			)
		)
		(pin "2"
		)
		(pin "6"
		)
		(pin "7"
		)
		(pin "5"
		)
		(pin "8"
		)
		(pin "4"
		)
		(pin "1"
		)
		(pin "3"
		)
		(instances
			(project "data-center-rdimm-ddr5-tester"
				(path ""
					(reference "U24")
					(unit 1)
				)
			)
		)
	)
	(symbol
		(lib_id "antmicroResistors0402:R_0R_0402")
		(at 292.1 201.93 180)
		(unit 1)
		(exclude_from_sim no)
		(in_bom no)
		(on_board yes)
		(dnp yes)
		(property "Reference" "R176"
			(at 291.465 200.66 0)
			(effects
				(font
					(size 1.27 1.27)
				)
				(justify right)
			)
		)
		(property "Value" "R_0R_0402"
			(at 271.78 189.23 0)
			(effects
				(font
					(size 1.27 1.27)
					(thickness 0.15)
				)
				(justify left bottom)
				(hide yes)
			)
		)
		(property "Footprint" "antmicro-footprints:R_0402_1005Metric"
			(at 271.78 186.69 0)
			(effects
				(font
					(size 1.27 1.27)
					(thickness 0.15)
				)
				(justify left bottom)
				(hide yes)
			)
		)
		(property "Datasheet" "https://industrial.panasonic.com/cdbs/www-data/pdf/RDA0000/AOA0000C301.pdf"
			(at 271.78 184.15 0)
			(effects
				(font
					(size 1.27 1.27)
					(thickness 0.15)
				)
				(justify left bottom)
				(hide yes)
			)
		)
		(property "Description" ""
			(at 292.1 201.93 0)
			(effects
				(font
					(size 1.27 1.27)
				)
				(hide yes)
			)
		)
		(property "Manufacturer" "Panasonic"
			(at 271.78 179.07 0)
			(effects
				(font
					(size 1.27 1.27)
					(thickness 0.15)
				)
				(justify left bottom)
				(hide yes)
			)
		)
		(property "MPN" "ERJ2GE0R00X"
			(at 271.78 181.61 0)
			(effects
				(font
					(size 1.27 1.27)
					(thickness 0.15)
				)
				(justify left bottom)
				(hide yes)
			)
		)
		(property "Val" "0R"
			(at 284.48 200.66 0)
			(effects
				(font
					(size 1.27 1.27)
					(thickness 0.15)
				)
				(justify right)
			)
		)
		(property "License" "Apache-2.0"
			(at 271.78 176.53 0)
			(effects
				(font
					(size 1.27 1.27)
					(thickness 0.15)
				)
				(justify left bottom)
				(hide yes)
			)
		)
		(property "Author" "Antmicro"
			(at 271.78 173.99 0)
			(effects
				(font
					(size 1.27 1.27)
					(thickness 0.15)
				)
				(justify left bottom)
				(hide yes)
			)
		)
		(property "Tolerance" "~"
			(at 271.78 191.77 0)
			(effects
				(font
					(size 1.27 1.27)
				)
				(justify left bottom)
				(hide yes)
			)
		)
		(property "Current" "1A"
			(at 293.3699 199.39 90)
			(effects
				(font
					(size 1.27 1.27)
					(thickness 0.15)
				)
				(justify right)
				(hide yes)
			)
		)
		(pin "1"
		)
		(pin "2"
		)
		(instances
			(project "data-center-rdimm-ddr5-tester"
				(path ""
					(reference "R176")
					(unit 1)
				)
			)
		)
	)
	(symbol
		(lib_id "antmicropower:+3V3_AON")
		(at 185.42 185.42 0)
		(mirror y)
		(unit 1)
		(exclude_from_sim no)
		(in_bom yes)
		(on_board yes)
		(dnp no)
		(fields_autoplaced yes)
		(property "Reference" "#PWR0441"
			(at 185.42 189.23 0)
			(effects
				(font
					(size 1.27 1.27)
				)
				(hide yes)
			)
		)
		(property "Value" "+3V3_AON"
			(at 185.42 179.705 0)
			(effects
				(font
					(size 1.27 1.27)
				)
			)
		)
		(property "Footprint" ""
			(at 185.42 185.42 0)
			(effects
				(font
					(size 1.27 1.27)
				)
				(hide yes)
			)
		)
		(property "Datasheet" ""
			(at 185.42 185.42 0)
			(effects
				(font
					(size 1.27 1.27)
				)
				(hide yes)
			)
		)
		(property "Description" ""
			(at 185.42 185.42 0)
			(effects
				(font
					(size 1.27 1.27)
				)
				(hide yes)
			)
		)
		(pin "1"
		)
		(instances
			(project "data-center-rdimm-ddr5-tester"
				(path ""
					(reference "#PWR0441")
					(unit 1)
				)
			)
		)
	)
	(symbol
		(lib_id "antmicropower:GND")
		(at 185.42 196.85 0)
		(mirror y)
		(unit 1)
		(exclude_from_sim no)
		(in_bom yes)
		(on_board yes)
		(dnp no)
		(fields_autoplaced yes)
		(property "Reference" "#PWR0437"
			(at 185.42 203.2 0)
			(effects
				(font
					(size 1.27 1.27)
				)
				(hide yes)
			)
		)
		(property "Value" "GND"
			(at 187.325 201.295 0)
			(effects
				(font
					(size 1.27 1.27)
					(thickness 0.15)
				)
				(justify left bottom)
			)
		)
		(property "Footprint" ""
			(at 176.53 204.47 0)
			(effects
				(font
					(size 1.27 1.27)
					(thickness 0.15)
				)
				(justify left bottom)
				(hide yes)
			)
		)
		(property "Datasheet" ""
			(at 176.53 209.55 0)
			(effects
				(font
					(size 1.27 1.27)
					(thickness 0.15)
				)
				(justify left bottom)
				(hide yes)
			)
		)
		(property "Description" ""
			(at 185.42 196.85 0)
			(effects
				(font
					(size 1.27 1.27)
				)
				(hide yes)
			)
		)
		(property "Author" "Antmicro"
			(at 176.53 201.93 0)
			(effects
				(font
					(size 1.27 1.27)
					(thickness 0.15)
				)
				(justify left bottom)
				(hide yes)
			)
		)
		(property "License" "Apache-2.0"
			(at 176.53 204.47 0)
			(effects
				(font
					(size 1.27 1.27)
					(thickness 0.15)
				)
				(justify left bottom)
				(hide yes)
			)
		)
		(pin "1"
		)
		(instances
			(project "data-center-rdimm-ddr5-tester"
				(path ""
					(reference "#PWR0437")
					(unit 1)
				)
			)
		)
	)
	(symbol
		(lib_id "antmicroCapacitors0402:C_100n_0402")
		(at 356.87 68.58 270)
		(mirror x)
		(unit 1)
		(exclude_from_sim no)
		(in_bom yes)
		(on_board yes)
		(dnp no)
		(property "Reference" "C324"
			(at 359.41 64.7636 90)
			(effects
				(font
					(size 1.27 1.27)
					(thickness 0.15)
				)
				(justify left)
			)
		)
		(property "Value" "C_100n_0402"
			(at 346.71 48.26 0)
			(effects
				(font
					(size 1.27 1.27)
					(thickness 0.15)
				)
				(justify left bottom)
				(hide yes)
			)
		)
		(property "Footprint" "antmicro-footprints:C_0402_1005Metric"
			(at 344.17 48.26 0)
			(effects
				(font
					(size 1.27 1.27)
					(thickness 0.15)
				)
				(justify left bottom)
				(hide yes)
			)
		)
		(property "Datasheet" "https://www.murata.com/products/productdetail?partno=GRM155R61H104KE14%23"
			(at 341.63 48.26 0)
			(effects
				(font
					(size 1.27 1.27)
					(thickness 0.15)
				)
				(justify left bottom)
				(hide yes)
			)
		)
		(property "Description" ""
			(at 356.87 68.58 0)
			(effects
				(font
					(size 1.27 1.27)
				)
				(hide yes)
			)
		)
		(property "MPN" "GRM155R61H104KE14D"
			(at 339.09 48.26 0)
			(effects
				(font
					(size 1.27 1.27)
					(thickness 0.15)
				)
				(justify left bottom)
				(hide yes)
			)
		)
		(property "Manufacturer" "Murata"
			(at 336.55 48.26 0)
			(effects
				(font
					(size 1.27 1.27)
					(thickness 0.15)
				)
				(justify left bottom)
				(hide yes)
			)
		)
		(property "License" "Apache-2.0"
			(at 334.01 48.26 0)
			(effects
				(font
					(size 1.27 1.27)
					(thickness 0.15)
				)
				(justify left bottom)
				(hide yes)
			)
		)
		(property "Author" "Antmicro"
			(at 331.47 48.26 0)
			(effects
				(font
					(size 1.27 1.27)
					(thickness 0.15)
				)
				(justify left bottom)
				(hide yes)
			)
		)
		(property "Val" "100n"
			(at 359.41 67.3036 90)
			(effects
				(font
					(size 1.27 1.27)
					(thickness 0.15)
				)
				(justify left)
			)
		)
		(property "Voltage" "50V"
			(at 328.93 48.26 0)
			(effects
				(font
					(size 1.27 1.27)
				)
				(justify left bottom)
				(hide yes)
			)
		)
		(property "Dielectric" "X5R"
			(at 326.39 48.26 0)
			(effects
				(font
					(size 1.27 1.27)
				)
				(justify left bottom)
				(hide yes)
			)
		)
		(pin "1"
		)
		(pin "2"
		)
		(instances
			(project "data-center-rdimm-ddr5-tester"
				(path ""
					(reference "C324")
					(unit 1)
				)
			)
		)
	)
	(symbol
		(lib_id "antmicroCapacitors0402:C_100n_0402")
		(at 269.24 74.93 270)
		(unit 1)
		(exclude_from_sim no)
		(in_bom yes)
		(on_board yes)
		(dnp no)
		(property "Reference" "C320"
			(at 266.7 76.2063 90)
			(effects
				(font
					(size 1.27 1.27)
				)
				(justify right)
			)
		)
		(property "Value" "C_100n_0402"
			(at 259.08 95.25 0)
			(effects
				(font
					(size 1.27 1.27)
					(thickness 0.15)
				)
				(justify left bottom)
				(hide yes)
			)
		)
		(property "Footprint" "antmicro-footprints:C_0402_1005Metric"
			(at 256.54 95.25 0)
			(effects
				(font
					(size 1.27 1.27)
					(thickness 0.15)
				)
				(justify left bottom)
				(hide yes)
			)
		)
		(property "Datasheet" "https://www.murata.com/products/productdetail?partno=GRM155R61H104KE14%23"
			(at 254 95.25 0)
			(effects
				(font
					(size 1.27 1.27)
					(thickness 0.15)
				)
				(justify left bottom)
				(hide yes)
			)
		)
		(property "Description" ""
			(at 269.24 74.93 0)
			(effects
				(font
					(size 1.27 1.27)
				)
				(hide yes)
			)
		)
		(property "Manufacturer" "Murata"
			(at 248.92 95.25 0)
			(effects
				(font
					(size 1.27 1.27)
					(thickness 0.15)
				)
				(justify left bottom)
				(hide yes)
			)
		)
		(property "MPN" "GRM155R61H104KE14D"
			(at 251.46 95.25 0)
			(effects
				(font
					(size 1.27 1.27)
					(thickness 0.15)
				)
				(justify left bottom)
				(hide yes)
			)
		)
		(property "Val" "100n"
			(at 266.7 79.3812 90)
			(effects
				(font
					(size 1.27 1.27)
					(thickness 0.15)
				)
				(justify right)
			)
		)
		(property "License" "Apache-2.0"
			(at 246.38 95.25 0)
			(effects
				(font
					(size 1.27 1.27)
					(thickness 0.15)
				)
				(justify left bottom)
				(hide yes)
			)
		)
		(property "Author" "Antmicro"
			(at 243.84 95.25 0)
			(effects
				(font
					(size 1.27 1.27)
					(thickness 0.15)
				)
				(justify left bottom)
				(hide yes)
			)
		)
		(property "Voltage" "50V"
			(at 241.3 95.25 0)
			(effects
				(font
					(size 1.27 1.27)
				)
				(justify left bottom)
				(hide yes)
			)
		)
		(property "Dielectric" "X5R"
			(at 238.76 95.25 0)
			(effects
				(font
					(size 1.27 1.27)
				)
				(justify left bottom)
				(hide yes)
			)
		)
		(pin "1"
		)
		(pin "2"
		)
		(instances
			(project "data-center-rdimm-ddr5-tester"
				(path ""
					(reference "C320")
					(unit 1)
				)
			)
		)
	)
	(symbol
		(lib_id "antmicropower:+3V3")
		(at 120.65 175.26 0)
		(unit 1)
		(exclude_from_sim no)
		(in_bom yes)
		(on_board yes)
		(dnp no)
		(fields_autoplaced yes)
		(property "Reference" "#PWR0442"
			(at 120.65 179.07 0)
			(effects
				(font
					(size 1.27 1.27)
				)
				(hide yes)
			)
		)
		(property "Value" "+3V3"
			(at 117.475 172.72 0)
			(effects
				(font
					(size 1.27 1.27)
					(thickness 0.15)
				)
				(justify left bottom)
			)
		)
		(property "Footprint" ""
			(at 135.89 182.88 0)
			(effects
				(font
					(size 1.27 1.27)
					(thickness 0.15)
				)
				(justify left bottom)
				(hide yes)
			)
		)
		(property "Datasheet" ""
			(at 135.89 185.42 0)
			(effects
				(font
					(size 1.27 1.27)
					(thickness 0.15)
				)
				(justify left bottom)
				(hide yes)
			)
		)
		(property "Description" ""
			(at 120.65 175.26 0)
			(effects
				(font
					(size 1.27 1.27)
				)
				(hide yes)
			)
		)
		(property "Author" "Antmicro"
			(at 135.89 177.8 0)
			(effects
				(font
					(size 1.27 1.27)
					(thickness 0.15)
				)
				(justify left bottom)
				(hide yes)
			)
		)
		(property "License" "Apache-2.0"
			(at 135.89 180.34 0)
			(effects
				(font
					(size 1.27 1.27)
					(thickness 0.15)
				)
				(justify left bottom)
				(hide yes)
			)
		)
		(pin "1"
		)
		(instances
			(project "data-center-rdimm-ddr5-tester"
				(path ""
					(reference "#PWR0442")
					(unit 1)
				)
			)
		)
	)
	(symbol
		(lib_id "antmicroResistors0402:R_4k7_0402")
		(at 238.76 76.2 90)
		(unit 1)
		(exclude_from_sim no)
		(in_bom yes)
		(on_board yes)
		(dnp no)
		(property "Reference" "R97"
			(at 240.03 72.39 90)
			(effects
				(font
					(size 1.27 1.27)
					(thickness 0.15)
				)
				(justify right)
			)
		)
		(property "Value" "R_4k7_0402"
			(at 251.46 55.88 0)
			(effects
				(font
					(size 1.27 1.27)
					(thickness 0.15)
				)
				(justify left bottom)
				(hide yes)
			)
		)
		(property "Footprint" "antmicro-footprints:R_0402_1005Metric"
			(at 254 55.88 0)
			(effects
				(font
					(size 1.27 1.27)
					(thickness 0.15)
				)
				(justify left bottom)
				(hide yes)
			)
		)
		(property "Datasheet" "https://www.bourns.com/docs/product-datasheets/cr.pdf"
			(at 256.54 55.88 0)
			(effects
				(font
					(size 1.27 1.27)
					(thickness 0.15)
				)
				(justify left bottom)
				(hide yes)
			)
		)
		(property "Description" ""
			(at 238.76 76.2 0)
			(effects
				(font
					(size 1.27 1.27)
				)
				(hide yes)
			)
		)
		(property "MPN" "CR0402-FX-4701GLF"
			(at 259.08 55.88 0)
			(effects
				(font
					(size 1.27 1.27)
					(thickness 0.15)
				)
				(justify left bottom)
				(hide yes)
			)
		)
		(property "Manufacturer" "Bourns"
			(at 261.62 55.88 0)
			(effects
				(font
					(size 1.27 1.27)
					(thickness 0.15)
				)
				(justify left bottom)
				(hide yes)
			)
		)
		(property "License" "Apache-2.0"
			(at 264.16 55.88 0)
			(effects
				(font
					(size 1.27 1.27)
					(thickness 0.15)
				)
				(justify left bottom)
				(hide yes)
			)
		)
		(property "Author" "Antmicro"
			(at 266.7 55.88 0)
			(effects
				(font
					(size 1.27 1.27)
					(thickness 0.15)
				)
				(justify left bottom)
				(hide yes)
			)
		)
		(property "Val" "4k7"
			(at 240.03 74.93 90)
			(effects
				(font
					(size 1.27 1.27)
					(thickness 0.15)
				)
				(justify right)
			)
		)
		(property "Tolerance" "1%"
			(at 248.92 55.88 0)
			(effects
				(font
					(size 1.27 1.27)
				)
				(justify left bottom)
				(hide yes)
			)
		)
		(pin "2"
		)
		(pin "1"
		)
		(instances
			(project "data-center-rdimm-ddr5-tester"
				(path ""
					(reference "R97")
					(unit 1)
				)
			)
		)
	)
	(symbol
		(lib_id "antmicroCapacitors0402:C_100n_0402")
		(at 185.42 218.44 270)
		(mirror x)
		(unit 1)
		(exclude_from_sim no)
		(in_bom yes)
		(on_board yes)
		(dnp no)
		(fields_autoplaced yes)
		(property "Reference" "C197"
			(at 182.88 214.6235 90)
			(effects
				(font
					(size 1.27 1.27)
				)
				(justify right)
			)
		)
		(property "Value" "C_100n_0402"
			(at 175.26 198.12 0)
			(effects
				(font
					(size 1.27 1.27)
					(thickness 0.15)
				)
				(justify left bottom)
				(hide yes)
			)
		)
		(property "Footprint" "antmicro-footprints:C_0402_1005Metric"
			(at 172.72 198.12 0)
			(effects
				(font
					(size 1.27 1.27)
					(thickness 0.15)
				)
				(justify left bottom)
				(hide yes)
			)
		)
		(property "Datasheet" "https://www.murata.com/products/productdetail?partno=GRM155R61H104KE14%23"
			(at 170.18 198.12 0)
			(effects
				(font
					(size 1.27 1.27)
					(thickness 0.15)
				)
				(justify left bottom)
				(hide yes)
			)
		)
		(property "Description" ""
			(at 185.42 218.44 0)
			(effects
				(font
					(size 1.27 1.27)
				)
				(hide yes)
			)
		)
		(property "Manufacturer" "Murata"
			(at 165.1 198.12 0)
			(effects
				(font
					(size 1.27 1.27)
					(thickness 0.15)
				)
				(justify left bottom)
				(hide yes)
			)
		)
		(property "MPN" "GRM155R61H104KE14D"
			(at 167.64 198.12 0)
			(effects
				(font
					(size 1.27 1.27)
					(thickness 0.15)
				)
				(justify left bottom)
				(hide yes)
			)
		)
		(property "Val" "100n"
			(at 182.88 217.1635 90)
			(effects
				(font
					(size 1.27 1.27)
					(thickness 0.15)
				)
				(justify right)
			)
		)
		(property "License" "Apache-2.0"
			(at 162.56 198.12 0)
			(effects
				(font
					(size 1.27 1.27)
					(thickness 0.15)
				)
				(justify left bottom)
				(hide yes)
			)
		)
		(property "Author" "Antmicro"
			(at 160.02 198.12 0)
			(effects
				(font
					(size 1.27 1.27)
					(thickness 0.15)
				)
				(justify left bottom)
				(hide yes)
			)
		)
		(property "Voltage" "50V"
			(at 157.48 198.12 0)
			(effects
				(font
					(size 1.27 1.27)
				)
				(justify left bottom)
				(hide yes)
			)
		)
		(property "Dielectric" "X5R"
			(at 154.94 198.12 0)
			(effects
				(font
					(size 1.27 1.27)
				)
				(justify left bottom)
				(hide yes)
			)
		)
		(pin "1"
		)
		(pin "2"
		)
		(instances
			(project "data-center-rdimm-ddr5-tester"
				(path ""
					(reference "C197")
					(unit 1)
				)
			)
		)
	)
	(symbol
		(lib_id "antmicroResistors0402:R_47k_0402")
		(at 325.12 68.58 90)
		(unit 1)
		(exclude_from_sim no)
		(in_bom yes)
		(on_board yes)
		(dnp no)
		(fields_autoplaced yes)
		(property "Reference" "R232"
			(at 322.58 64.77 90)
			(effects
				(font
					(size 1.27 1.27)
					(thickness 0.15)
				)
				(justify left)
			)
		)
		(property "Value" "R_47k_0402"
			(at 337.82 48.26 0)
			(effects
				(font
					(size 1.27 1.27)
					(thickness 0.15)
				)
				(justify left bottom)
				(hide yes)
			)
		)
		(property "Footprint" "antmicro-footprints:R_0402_1005Metric"
			(at 340.36 48.26 0)
			(effects
				(font
					(size 1.27 1.27)
					(thickness 0.15)
				)
				(justify left bottom)
				(hide yes)
			)
		)
		(property "Datasheet" "https://www.bourns.com/docs/product-datasheets/cr.pdf"
			(at 342.9 48.26 0)
			(effects
				(font
					(size 1.27 1.27)
					(thickness 0.15)
				)
				(justify left bottom)
				(hide yes)
			)
		)
		(property "Description" ""
			(at 325.12 68.58 0)
			(effects
				(font
					(size 1.27 1.27)
				)
				(hide yes)
			)
		)
		(property "MPN" "CR0402-FX-4702GLF"
			(at 345.44 48.26 0)
			(effects
				(font
					(size 1.27 1.27)
					(thickness 0.15)
				)
				(justify left bottom)
				(hide yes)
			)
		)
		(property "Manufacturer" "Bourns"
			(at 347.98 48.26 0)
			(effects
				(font
					(size 1.27 1.27)
					(thickness 0.15)
				)
				(justify left bottom)
				(hide yes)
			)
		)
		(property "License" "Apache-2.0"
			(at 350.52 48.26 0)
			(effects
				(font
					(size 1.27 1.27)
					(thickness 0.15)
				)
				(justify left bottom)
				(hide yes)
			)
		)
		(property "Author" "Antmicro"
			(at 353.06 48.26 0)
			(effects
				(font
					(size 1.27 1.27)
					(thickness 0.15)
				)
				(justify left bottom)
				(hide yes)
			)
		)
		(property "Val" "47k"
			(at 322.58 67.31 90)
			(effects
				(font
					(size 1.27 1.27)
					(thickness 0.15)
				)
				(justify left)
			)
		)
		(property "Tolerance" "1%"
			(at 335.28 48.26 0)
			(effects
				(font
					(size 1.27 1.27)
				)
				(justify left bottom)
				(hide yes)
			)
		)
		(pin "2"
		)
		(pin "1"
		)
		(instances
			(project "data-center-rdimm-ddr5-tester"
				(path ""
					(reference "R232")
					(unit 1)
				)
			)
		)
	)
	(symbol
		(lib_id "antmicroResistors0402:R_0R_0402")
		(at 129.54 57.15 270)
		(mirror x)
		(unit 1)
		(exclude_from_sim no)
		(in_bom yes)
		(on_board yes)
		(dnp no)
		(fields_autoplaced yes)
		(property "Reference" "R127"
			(at 131.191 53.7794 90)
			(effects
				(font
					(size 1.27 1.27)
					(thickness 0.15)
				)
				(justify left)
			)
		)
		(property "Value" "R_0R_0402"
			(at 116.84 36.83 0)
			(effects
				(font
					(size 1.27 1.27)
					(thickness 0.15)
				)
				(justify left bottom)
				(hide yes)
			)
		)
		(property "Footprint" "antmicro-footprints:R_0402_1005Metric"
			(at 114.3 36.83 0)
			(effects
				(font
					(size 1.27 1.27)
					(thickness 0.15)
				)
				(justify left bottom)
				(hide yes)
			)
		)
		(property "Datasheet" "https://industrial.panasonic.com/cdbs/www-data/pdf/RDA0000/AOA0000C301.pdf"
			(at 111.76 36.83 0)
			(effects
				(font
					(size 1.27 1.27)
					(thickness 0.15)
				)
				(justify left bottom)
				(hide yes)
			)
		)
		(property "Description" ""
			(at 129.54 57.15 0)
			(effects
				(font
					(size 1.27 1.27)
				)
				(hide yes)
			)
		)
		(property "MPN" "ERJ2GE0R00X"
			(at 109.22 36.83 0)
			(effects
				(font
					(size 1.27 1.27)
					(thickness 0.15)
				)
				(justify left bottom)
				(hide yes)
			)
		)
		(property "Manufacturer" "Panasonic"
			(at 106.68 36.83 0)
			(effects
				(font
					(size 1.27 1.27)
					(thickness 0.15)
				)
				(justify left bottom)
				(hide yes)
			)
		)
		(property "License" "Apache-2.0"
			(at 104.14 36.83 0)
			(effects
				(font
					(size 1.27 1.27)
					(thickness 0.15)
				)
				(justify left bottom)
				(hide yes)
			)
		)
		(property "Author" "Antmicro"
			(at 101.6 36.83 0)
			(effects
				(font
					(size 1.27 1.27)
					(thickness 0.15)
				)
				(justify left bottom)
				(hide yes)
			)
		)
		(property "Val" "0R"
			(at 131.191 56.3031 90)
			(effects
				(font
					(size 1.27 1.27)
					(thickness 0.15)
				)
				(justify left)
			)
		)
		(property "Tolerance" "~"
			(at 119.38 36.83 0)
			(effects
				(font
					(size 1.27 1.27)
				)
				(justify left bottom)
				(hide yes)
			)
		)
		(property "Current" "1A"
			(at 99.06 36.83 0)
			(effects
				(font
					(size 1.27 1.27)
					(thickness 0.15)
				)
				(justify left bottom)
				(hide yes)
			)
		)
		(pin "1"
		)
		(pin "2"
		)
		(instances
			(project "data-center-rdimm-ddr5-tester"
				(path ""
					(reference "R127")
					(unit 1)
				)
			)
		)
	)
	(symbol
		(lib_id "antmicroResistors0402:R_4k7_0402")
		(at 246.38 76.2 90)
		(unit 1)
		(exclude_from_sim no)
		(in_bom yes)
		(on_board yes)
		(dnp no)
		(property "Reference" "R231"
			(at 247.65 72.39 90)
			(effects
				(font
					(size 1.27 1.27)
					(thickness 0.15)
				)
				(justify right)
			)
		)
		(property "Value" "R_4k7_0402"
			(at 259.08 55.88 0)
			(effects
				(font
					(size 1.27 1.27)
					(thickness 0.15)
				)
				(justify left bottom)
				(hide yes)
			)
		)
		(property "Footprint" "antmicro-footprints:R_0402_1005Metric"
			(at 261.62 55.88 0)
			(effects
				(font
					(size 1.27 1.27)
					(thickness 0.15)
				)
				(justify left bottom)
				(hide yes)
			)
		)
		(property "Datasheet" "https://www.bourns.com/docs/product-datasheets/cr.pdf"
			(at 264.16 55.88 0)
			(effects
				(font
					(size 1.27 1.27)
					(thickness 0.15)
				)
				(justify left bottom)
				(hide yes)
			)
		)
		(property "Description" ""
			(at 246.38 76.2 0)
			(effects
				(font
					(size 1.27 1.27)
				)
				(hide yes)
			)
		)
		(property "MPN" "CR0402-FX-4701GLF"
			(at 266.7 55.88 0)
			(effects
				(font
					(size 1.27 1.27)
					(thickness 0.15)
				)
				(justify left bottom)
				(hide yes)
			)
		)
		(property "Manufacturer" "Bourns"
			(at 269.24 55.88 0)
			(effects
				(font
					(size 1.27 1.27)
					(thickness 0.15)
				)
				(justify left bottom)
				(hide yes)
			)
		)
		(property "License" "Apache-2.0"
			(at 271.78 55.88 0)
			(effects
				(font
					(size 1.27 1.27)
					(thickness 0.15)
				)
				(justify left bottom)
				(hide yes)
			)
		)
		(property "Author" "Antmicro"
			(at 274.32 55.88 0)
			(effects
				(font
					(size 1.27 1.27)
					(thickness 0.15)
				)
				(justify left bottom)
				(hide yes)
			)
		)
		(property "Val" "4k7"
			(at 247.65 74.93 90)
			(effects
				(font
					(size 1.27 1.27)
					(thickness 0.15)
				)
				(justify right)
			)
		)
		(property "Tolerance" "1%"
			(at 256.54 55.88 0)
			(effects
				(font
					(size 1.27 1.27)
				)
				(justify left bottom)
				(hide yes)
			)
		)
		(pin "2"
		)
		(pin "1"
		)
		(instances
			(project "data-center-rdimm-ddr5-tester"
				(path ""
					(reference "R231")
					(unit 1)
				)
			)
		)
	)
	(symbol
		(lib_id "antmicropower:PWR_FLAG")
		(at 300.99 72.39 0)
		(unit 1)
		(exclude_from_sim no)
		(in_bom yes)
		(on_board yes)
		(dnp no)
		(property "Reference" "#FLG018"
			(at 300.99 70.485 0)
			(effects
				(font
					(size 1.27 1.27)
				)
				(hide yes)
			)
		)
		(property "Value" "PWR_FLAG"
			(at 302.26 68.834 0)
			(effects
				(font
					(size 1.27 1.27)
				)
			)
		)
		(property "Footprint" ""
			(at 300.99 72.39 0)
			(effects
				(font
					(size 1.27 1.27)
				)
				(hide yes)
			)
		)
		(property "Datasheet" ""
			(at 300.99 72.39 0)
			(effects
				(font
					(size 1.27 1.27)
				)
				(hide yes)
			)
		)
		(property "Description" ""
			(at 300.99 72.39 0)
			(effects
				(font
					(size 1.27 1.27)
				)
				(hide yes)
			)
		)
		(pin "1"
		)
		(instances
			(project "data-center-rdimm-ddr5-tester"
				(path ""
					(reference "#FLG018")
					(unit 1)
				)
			)
		)
	)
	(symbol
		(lib_id "antmicroResistors0402:R_0R_0402")
		(at 292.1 196.85 180)
		(unit 1)
		(exclude_from_sim no)
		(in_bom no)
		(on_board yes)
		(dnp yes)
		(property "Reference" "R174"
			(at 291.465 195.58 0)
			(effects
				(font
					(size 1.27 1.27)
				)
				(justify right)
			)
		)
		(property "Value" "R_0R_0402"
			(at 271.78 184.15 0)
			(effects
				(font
					(size 1.27 1.27)
					(thickness 0.15)
				)
				(justify left bottom)
				(hide yes)
			)
		)
		(property "Footprint" "antmicro-footprints:R_0402_1005Metric"
			(at 271.78 181.61 0)
			(effects
				(font
					(size 1.27 1.27)
					(thickness 0.15)
				)
				(justify left bottom)
				(hide yes)
			)
		)
		(property "Datasheet" "https://industrial.panasonic.com/cdbs/www-data/pdf/RDA0000/AOA0000C301.pdf"
			(at 271.78 179.07 0)
			(effects
				(font
					(size 1.27 1.27)
					(thickness 0.15)
				)
				(justify left bottom)
				(hide yes)
			)
		)
		(property "Description" ""
			(at 292.1 196.85 0)
			(effects
				(font
					(size 1.27 1.27)
				)
				(hide yes)
			)
		)
		(property "Manufacturer" "Panasonic"
			(at 271.78 173.99 0)
			(effects
				(font
					(size 1.27 1.27)
					(thickness 0.15)
				)
				(justify left bottom)
				(hide yes)
			)
		)
		(property "MPN" "ERJ2GE0R00X"
			(at 271.78 176.53 0)
			(effects
				(font
					(size 1.27 1.27)
					(thickness 0.15)
				)
				(justify left bottom)
				(hide yes)
			)
		)
		(property "Val" "0R"
			(at 284.48 195.58 0)
			(effects
				(font
					(size 1.27 1.27)
					(thickness 0.15)
				)
				(justify right)
			)
		)
		(property "License" "Apache-2.0"
			(at 271.78 171.45 0)
			(effects
				(font
					(size 1.27 1.27)
					(thickness 0.15)
				)
				(justify left bottom)
				(hide yes)
			)
		)
		(property "Author" "Antmicro"
			(at 271.78 168.91 0)
			(effects
				(font
					(size 1.27 1.27)
					(thickness 0.15)
				)
				(justify left bottom)
				(hide yes)
			)
		)
		(property "Tolerance" "~"
			(at 271.78 186.69 0)
			(effects
				(font
					(size 1.27 1.27)
				)
				(justify left bottom)
				(hide yes)
			)
		)
		(property "Current" "1A"
			(at 293.3699 194.31 90)
			(effects
				(font
					(size 1.27 1.27)
					(thickness 0.15)
				)
				(justify right)
				(hide yes)
			)
		)
		(pin "1"
		)
		(pin "2"
		)
		(instances
			(project "data-center-rdimm-ddr5-tester"
				(path ""
					(reference "R174")
					(unit 1)
				)
			)
		)
	)
	(symbol
		(lib_id "antmicropower:GND")
		(at 171.45 200.66 0)
		(unit 1)
		(exclude_from_sim no)
		(in_bom yes)
		(on_board yes)
		(dnp no)
		(property "Reference" "#PWR0436"
			(at 171.45 207.01 0)
			(effects
				(font
					(size 1.27 1.27)
				)
				(hide yes)
			)
		)
		(property "Value" "GND"
			(at 169.545 205.105 0)
			(effects
				(font
					(size 1.27 1.27)
					(thickness 0.15)
				)
				(justify left bottom)
			)
		)
		(property "Footprint" ""
			(at 180.34 208.28 0)
			(effects
				(font
					(size 1.27 1.27)
					(thickness 0.15)
				)
				(justify left bottom)
				(hide yes)
			)
		)
		(property "Datasheet" ""
			(at 180.34 213.36 0)
			(effects
				(font
					(size 1.27 1.27)
					(thickness 0.15)
				)
				(justify left bottom)
				(hide yes)
			)
		)
		(property "Description" ""
			(at 171.45 200.66 0)
			(effects
				(font
					(size 1.27 1.27)
				)
				(hide yes)
			)
		)
		(property "Author" "Antmicro"
			(at 180.34 205.74 0)
			(effects
				(font
					(size 1.27 1.27)
					(thickness 0.15)
				)
				(justify left bottom)
				(hide yes)
			)
		)
		(property "License" "Apache-2.0"
			(at 180.34 208.28 0)
			(effects
				(font
					(size 1.27 1.27)
					(thickness 0.15)
				)
				(justify left bottom)
				(hide yes)
			)
		)
		(pin "1"
		)
		(instances
			(project "data-center-rdimm-ddr5-tester"
				(path ""
					(reference "#PWR0436")
					(unit 1)
				)
			)
		)
	)
	(symbol
		(lib_id "antmicropower:PWR_FLAG")
		(at 275.59 72.39 0)
		(unit 1)
		(exclude_from_sim no)
		(in_bom yes)
		(on_board yes)
		(dnp no)
		(fields_autoplaced yes)
		(property "Reference" "#FLG017"
			(at 275.59 70.485 0)
			(effects
				(font
					(size 1.27 1.27)
				)
				(hide yes)
			)
		)
		(property "Value" "PWR_FLAG"
			(at 275.59 68.8142 0)
			(effects
				(font
					(size 1.27 1.27)
				)
			)
		)
		(property "Footprint" ""
			(at 275.59 72.39 0)
			(effects
				(font
					(size 1.27 1.27)
				)
				(hide yes)
			)
		)
		(property "Datasheet" ""
			(at 275.59 72.39 0)
			(effects
				(font
					(size 1.27 1.27)
				)
				(hide yes)
			)
		)
		(property "Description" ""
			(at 275.59 72.39 0)
			(effects
				(font
					(size 1.27 1.27)
				)
				(hide yes)
			)
		)
		(pin "1"
		)
		(instances
			(project "data-center-rdimm-ddr5-tester"
				(path ""
					(reference "#FLG017")
					(unit 1)
				)
			)
		)
	)
	(symbol
		(lib_id "antmicropower:GND")
		(at 369.57 91.44 0)
		(mirror y)
		(unit 1)
		(exclude_from_sim no)
		(in_bom yes)
		(on_board yes)
		(dnp no)
		(fields_autoplaced yes)
		(property "Reference" "#PWR0530"
			(at 369.57 97.79 0)
			(effects
				(font
					(size 1.27 1.27)
				)
				(hide yes)
			)
		)
		(property "Value" "GND"
			(at 371.475 95.885 0)
			(effects
				(font
					(size 1.27 1.27)
					(thickness 0.15)
				)
				(justify left bottom)
			)
		)
		(property "Footprint" ""
			(at 360.68 99.06 0)
			(effects
				(font
					(size 1.27 1.27)
					(thickness 0.15)
				)
				(justify left bottom)
				(hide yes)
			)
		)
		(property "Datasheet" ""
			(at 360.68 104.14 0)
			(effects
				(font
					(size 1.27 1.27)
					(thickness 0.15)
				)
				(justify left bottom)
				(hide yes)
			)
		)
		(property "Description" ""
			(at 369.57 91.44 0)
			(effects
				(font
					(size 1.27 1.27)
				)
				(hide yes)
			)
		)
		(property "Author" "Antmicro"
			(at 360.68 96.52 0)
			(effects
				(font
					(size 1.27 1.27)
					(thickness 0.15)
				)
				(justify left bottom)
				(hide yes)
			)
		)
		(property "License" "Apache-2.0"
			(at 360.68 99.06 0)
			(effects
				(font
					(size 1.27 1.27)
					(thickness 0.15)
				)
				(justify left bottom)
				(hide yes)
			)
		)
		(pin "1"
		)
		(instances
			(project "data-center-rdimm-ddr5-tester"
				(path ""
					(reference "#PWR0530")
					(unit 1)
				)
			)
		)
	)
	(symbol
		(lib_id "antmicroTestPoints:TP_0.75mm_SMD")
		(at 123.19 50.8 90)
		(unit 1)
		(exclude_from_sim no)
		(in_bom no)
		(on_board yes)
		(dnp no)
		(property "Reference" "TP27"
			(at 120.65 45.72 90)
			(effects
				(font
					(size 1.27 1.27)
					(thickness 0.15)
				)
				(justify right)
			)
		)
		(property "Value" "TP_0.75mm_SMD"
			(at 127 40.64 0)
			(effects
				(font
					(size 1.27 1.27)
					(thickness 0.15)
				)
				(justify left bottom)
				(hide yes)
			)
		)
		(property "Footprint" "antmicro-footprints:TP_SMD_0.75mm"
			(at 129.54 40.64 0)
			(effects
				(font
					(size 1.27 1.27)
					(thickness 0.15)
				)
				(justify left bottom)
				(hide yes)
			)
		)
		(property "Datasheet" ""
			(at 135.89 33.02 0)
			(effects
				(font
					(size 1.27 1.27)
					(thickness 0.15)
				)
				(justify left bottom)
				(hide yes)
			)
		)
		(property "Description" ""
			(at 123.19 50.8 0)
			(effects
				(font
					(size 1.27 1.27)
				)
				(hide yes)
			)
		)
		(property "MPN" ""
			(at 134.62 40.005 0)
			(effects
				(font
					(size 1.27 1.27)
					(thickness 0.15)
				)
				(justify left bottom)
				(hide yes)
			)
		)
		(property "Manufacturer" ""
			(at 129.54 40.005 0)
			(effects
				(font
					(size 1.27 1.27)
					(thickness 0.15)
				)
				(justify left bottom)
				(hide yes)
			)
		)
		(property "Author" "Antmicro"
			(at 132.08 40.64 0)
			(effects
				(font
					(size 1.27 1.27)
					(thickness 0.15)
				)
				(justify left bottom)
				(hide yes)
			)
		)
		(property "License" "Apache-2.0"
			(at 134.62 40.64 0)
			(effects
				(font
					(size 1.27 1.27)
					(thickness 0.15)
				)
				(justify left bottom)
				(hide yes)
			)
		)
		(pin "1"
		)
		(instances
			(project "data-center-rdimm-ddr5-tester"
				(path ""
					(reference "TP27")
					(unit 1)
				)
			)
		)
	)
	(symbol
		(lib_id "antmicroLogicTranslatorsLevelShifters:PCA9517ADP")
		(at 96.52 92.71 0)
		(mirror y)
		(unit 1)
		(exclude_from_sim no)
		(in_bom yes)
		(on_board yes)
		(dnp no)
		(property "Reference" "U45"
			(at 87.63 85.09 0)
			(effects
				(font
					(size 1.27 1.27)
					(thickness 0.15)
				)
			)
		)
		(property "Value" "PCA9517ADP"
			(at 63.5 97.79 0)
			(effects
				(font
					(size 1.27 1.27)
					(thickness 0.15)
				)
				(justify left bottom)
				(hide yes)
			)
		)
		(property "Footprint" "antmicro-footprints:TSSOP-8_3x3mm_P0.65mm"
			(at 63.5 100.33 0)
			(effects
				(font
					(size 1.27 1.27)
					(thickness 0.15)
				)
				(justify left bottom)
				(hide yes)
			)
		)
		(property "Datasheet" "https://www.nxp.com/docs/en/data-sheet/PCA9517A.pdf"
			(at 63.5 102.87 0)
			(effects
				(font
					(size 1.27 1.27)
					(thickness 0.15)
				)
				(justify left bottom)
				(hide yes)
			)
		)
		(property "Description" ""
			(at 96.52 92.71 0)
			(effects
				(font
					(size 1.27 1.27)
				)
				(hide yes)
			)
		)
		(property "MPN" "PCA9517ADP,118"
			(at 87.63 87.63 0)
			(effects
				(font
					(size 1.27 1.27)
					(thickness 0.15)
				)
			)
		)
		(property "Manufacturer" "NXP"
			(at 63.5 107.95 0)
			(effects
				(font
					(size 1.27 1.27)
					(thickness 0.15)
				)
				(justify left bottom)
				(hide yes)
			)
		)
		(property "Author" "Antmicro"
			(at 63.5 110.49 0)
			(effects
				(font
					(size 1.27 1.27)
					(thickness 0.15)
				)
				(justify left bottom)
				(hide yes)
			)
		)
		(property "License" "Apache-2.0"
			(at 63.5 113.03 0)
			(effects
				(font
					(size 1.27 1.27)
					(thickness 0.15)
				)
				(justify left bottom)
				(hide yes)
			)
		)
		(pin "7"
		)
		(pin "1"
		)
		(pin "2"
		)
		(pin "3"
		)
		(pin "8"
		)
		(pin "6"
		)
		(pin "5"
		)
		(pin "4"
		)
		(instances
			(project "data-center-rdimm-ddr5-tester"
				(path ""
					(reference "U45")
					(unit 1)
				)
			)
		)
	)
	(symbol
		(lib_id "antmicropower:GND")
		(at 269.24 80.01 0)
		(unit 1)
		(exclude_from_sim no)
		(in_bom yes)
		(on_board yes)
		(dnp no)
		(fields_autoplaced yes)
		(property "Reference" "#PWR0515"
			(at 269.24 86.36 0)
			(effects
				(font
					(size 1.27 1.27)
				)
				(hide yes)
			)
		)
		(property "Value" "GND"
			(at 267.335 84.455 0)
			(effects
				(font
					(size 1.27 1.27)
					(thickness 0.15)
				)
				(justify left bottom)
			)
		)
		(property "Footprint" ""
			(at 278.13 87.63 0)
			(effects
				(font
					(size 1.27 1.27)
					(thickness 0.15)
				)
				(justify left bottom)
				(hide yes)
			)
		)
		(property "Datasheet" ""
			(at 278.13 92.71 0)
			(effects
				(font
					(size 1.27 1.27)
					(thickness 0.15)
				)
				(justify left bottom)
				(hide yes)
			)
		)
		(property "Description" ""
			(at 269.24 80.01 0)
			(effects
				(font
					(size 1.27 1.27)
				)
				(hide yes)
			)
		)
		(property "Author" "Antmicro"
			(at 278.13 85.09 0)
			(effects
				(font
					(size 1.27 1.27)
					(thickness 0.15)
				)
				(justify left bottom)
				(hide yes)
			)
		)
		(property "License" "Apache-2.0"
			(at 278.13 87.63 0)
			(effects
				(font
					(size 1.27 1.27)
					(thickness 0.15)
				)
				(justify left bottom)
				(hide yes)
			)
		)
		(pin "1"
		)
		(instances
			(project "data-center-rdimm-ddr5-tester"
				(path ""
					(reference "#PWR0515")
					(unit 1)
				)
			)
		)
	)
	(symbol
		(lib_id "antmicropower:+3V3")
		(at 344.17 102.87 0)
		(unit 1)
		(exclude_from_sim no)
		(in_bom yes)
		(on_board yes)
		(dnp no)
		(property "Reference" "#PWR0511"
			(at 359.41 102.87 0)
			(effects
				(font
					(size 1.27 1.27)
					(thickness 0.15)
				)
				(justify left bottom)
				(hide yes)
			)
		)
		(property "Value" "+3V3"
			(at 344.17 99.06 0)
			(effects
				(font
					(size 1.27 1.27)
					(thickness 0.15)
				)
			)
		)
		(property "Footprint" ""
			(at 359.41 110.49 0)
			(effects
				(font
					(size 1.27 1.27)
					(thickness 0.15)
				)
				(justify left bottom)
				(hide yes)
			)
		)
		(property "Datasheet" ""
			(at 359.41 113.03 0)
			(effects
				(font
					(size 1.27 1.27)
					(thickness 0.15)
				)
				(justify left bottom)
				(hide yes)
			)
		)
		(property "Description" ""
			(at 344.17 102.87 0)
			(effects
				(font
					(size 1.27 1.27)
				)
				(hide yes)
			)
		)
		(property "Author" "Antmicro"
			(at 359.41 105.41 0)
			(effects
				(font
					(size 1.27 1.27)
					(thickness 0.15)
				)
				(justify left bottom)
				(hide yes)
			)
		)
		(property "License" "Apache-2.0"
			(at 359.41 107.95 0)
			(effects
				(font
					(size 1.27 1.27)
					(thickness 0.15)
				)
				(justify left bottom)
				(hide yes)
			)
		)
		(pin "1"
		)
		(instances
			(project "data-center-rdimm-ddr5-tester"
				(path ""
					(reference "#PWR0511")
					(unit 1)
				)
			)
		)
	)
	(symbol
		(lib_id "antmicroCapacitors0402:C_100n_0402")
		(at 300.99 74.93 90)
		(mirror x)
		(unit 1)
		(exclude_from_sim no)
		(in_bom yes)
		(on_board yes)
		(dnp no)
		(fields_autoplaced yes)
		(property "Reference" "C322"
			(at 303.3141 76.6457 90)
			(effects
				(font
					(size 1.27 1.27)
				)
				(justify right)
			)
		)
		(property "Value" "C_100n_0402"
			(at 311.15 95.25 0)
			(effects
				(font
					(size 1.27 1.27)
					(thickness 0.15)
				)
				(justify left bottom)
				(hide yes)
			)
		)
		(property "Footprint" "antmicro-footprints:C_0402_1005Metric"
			(at 313.69 95.25 0)
			(effects
				(font
					(size 1.27 1.27)
					(thickness 0.15)
				)
				(justify left bottom)
				(hide yes)
			)
		)
		(property "Datasheet" "https://www.murata.com/products/productdetail?partno=GRM155R61H104KE14%23"
			(at 316.23 95.25 0)
			(effects
				(font
					(size 1.27 1.27)
					(thickness 0.15)
				)
				(justify left bottom)
				(hide yes)
			)
		)
		(property "Description" ""
			(at 300.99 74.93 0)
			(effects
				(font
					(size 1.27 1.27)
				)
				(hide yes)
			)
		)
		(property "Manufacturer" "Murata"
			(at 321.31 95.25 0)
			(effects
				(font
					(size 1.27 1.27)
					(thickness 0.15)
				)
				(justify left bottom)
				(hide yes)
			)
		)
		(property "MPN" "GRM155R61H104KE14D"
			(at 318.77 95.25 0)
			(effects
				(font
					(size 1.27 1.27)
					(thickness 0.15)
				)
				(justify left bottom)
				(hide yes)
			)
		)
		(property "Val" "100n"
			(at 303.3141 79.176 90)
			(effects
				(font
					(size 1.27 1.27)
					(thickness 0.15)
				)
				(justify right)
			)
		)
		(property "License" "Apache-2.0"
			(at 323.85 95.25 0)
			(effects
				(font
					(size 1.27 1.27)
					(thickness 0.15)
				)
				(justify left bottom)
				(hide yes)
			)
		)
		(property "Author" "Antmicro"
			(at 326.39 95.25 0)
			(effects
				(font
					(size 1.27 1.27)
					(thickness 0.15)
				)
				(justify left bottom)
				(hide yes)
			)
		)
		(property "Voltage" "50V"
			(at 328.93 95.25 0)
			(effects
				(font
					(size 1.27 1.27)
				)
				(justify left bottom)
				(hide yes)
			)
		)
		(property "Dielectric" "X5R"
			(at 331.47 95.25 0)
			(effects
				(font
					(size 1.27 1.27)
				)
				(justify left bottom)
				(hide yes)
			)
		)
		(pin "1"
		)
		(pin "2"
		)
		(instances
			(project "data-center-rdimm-ddr5-tester"
				(path ""
					(reference "C322")
					(unit 1)
				)
			)
		)
	)
	(symbol
		(lib_id "antmicropower:+3V3")
		(at 49.53 50.8 0)
		(unit 1)
		(exclude_from_sim no)
		(in_bom yes)
		(on_board yes)
		(dnp no)
		(fields_autoplaced yes)
		(property "Reference" "#PWR0267"
			(at 49.53 54.61 0)
			(effects
				(font
					(size 1.27 1.27)
				)
				(hide yes)
			)
		)
		(property "Value" "+3V3"
			(at 46.355 48.26 0)
			(effects
				(font
					(size 1.27 1.27)
					(thickness 0.15)
				)
				(justify left bottom)
			)
		)
		(property "Footprint" ""
			(at 64.77 58.42 0)
			(effects
				(font
					(size 1.27 1.27)
					(thickness 0.15)
				)
				(justify left bottom)
				(hide yes)
			)
		)
		(property "Datasheet" ""
			(at 64.77 60.96 0)
			(effects
				(font
					(size 1.27 1.27)
					(thickness 0.15)
				)
				(justify left bottom)
				(hide yes)
			)
		)
		(property "Description" ""
			(at 49.53 50.8 0)
			(effects
				(font
					(size 1.27 1.27)
				)
				(hide yes)
			)
		)
		(property "Author" "Antmicro"
			(at 64.77 53.34 0)
			(effects
				(font
					(size 1.27 1.27)
					(thickness 0.15)
				)
				(justify left bottom)
				(hide yes)
			)
		)
		(property "License" "Apache-2.0"
			(at 64.77 55.88 0)
			(effects
				(font
					(size 1.27 1.27)
					(thickness 0.15)
				)
				(justify left bottom)
				(hide yes)
			)
		)
		(pin "1"
		)
		(instances
			(project "data-center-rdimm-ddr5-tester"
				(path ""
					(reference "#PWR0267")
					(unit 1)
				)
			)
		)
	)
	(symbol
		(lib_id "antmicropower:GND")
		(at 300.99 80.01 0)
		(unit 1)
		(exclude_from_sim no)
		(in_bom yes)
		(on_board yes)
		(dnp no)
		(fields_autoplaced yes)
		(property "Reference" "#PWR0522"
			(at 300.99 86.36 0)
			(effects
				(font
					(size 1.27 1.27)
				)
				(hide yes)
			)
		)
		(property "Value" "GND"
			(at 299.085 84.455 0)
			(effects
				(font
					(size 1.27 1.27)
					(thickness 0.15)
				)
				(justify left bottom)
			)
		)
		(property "Footprint" ""
			(at 309.88 87.63 0)
			(effects
				(font
					(size 1.27 1.27)
					(thickness 0.15)
				)
				(justify left bottom)
				(hide yes)
			)
		)
		(property "Datasheet" ""
			(at 309.88 92.71 0)
			(effects
				(font
					(size 1.27 1.27)
					(thickness 0.15)
				)
				(justify left bottom)
				(hide yes)
			)
		)
		(property "Description" ""
			(at 300.99 80.01 0)
			(effects
				(font
					(size 1.27 1.27)
				)
				(hide yes)
			)
		)
		(property "Author" "Antmicro"
			(at 309.88 85.09 0)
			(effects
				(font
					(size 1.27 1.27)
					(thickness 0.15)
				)
				(justify left bottom)
				(hide yes)
			)
		)
		(property "License" "Apache-2.0"
			(at 309.88 87.63 0)
			(effects
				(font
					(size 1.27 1.27)
					(thickness 0.15)
				)
				(justify left bottom)
				(hide yes)
			)
		)
		(pin "1"
		)
		(instances
			(project "data-center-rdimm-ddr5-tester"
				(path ""
					(reference "#PWR0522")
					(unit 1)
				)
			)
		)
	)
	(symbol
		(lib_id "antmicroTransistorsFETsMOSFETsSingle:BSS84AKW")
		(at 228.6 68.58 270)
		(mirror x)
		(unit 1)
		(exclude_from_sim no)
		(in_bom yes)
		(on_board yes)
		(dnp no)
		(property "Reference" "Q22"
			(at 231.14 54.61 90)
			(effects
				(font
					(size 1.27 1.27)
					(thickness 0.15)
				)
			)
		)
		(property "Value" "BSS84AKW"
			(at 220.98 45.72 0)
			(effects
				(font
					(size 1.27 1.27)
					(thickness 0.15)
				)
				(justify left bottom)
				(hide yes)
			)
		)
		(property "Footprint" "antmicro-footprints:SOT-323"
			(at 218.44 45.72 0)
			(effects
				(font
					(size 1.27 1.27)
					(thickness 0.15)
				)
				(justify left bottom)
				(hide yes)
			)
		)
		(property "Datasheet" "https://assets.nexperia.com/documents/data-sheet/BSS84AKW.pdf"
			(at 215.9 45.72 0)
			(effects
				(font
					(size 1.27 1.27)
					(thickness 0.15)
				)
				(justify left bottom)
				(hide yes)
			)
		)
		(property "Description" ""
			(at 228.6 68.58 0)
			(effects
				(font
					(size 1.27 1.27)
				)
				(hide yes)
			)
		)
		(property "MPN" "BSS84AKW,115"
			(at 231.14 57.15 90)
			(effects
				(font
					(size 1.27 1.27)
					(thickness 0.15)
				)
			)
		)
		(property "Manufacturer" "Nexperia"
			(at 213.36 45.72 0)
			(effects
				(font
					(size 1.27 1.27)
					(thickness 0.15)
				)
				(justify left bottom)
				(hide yes)
			)
		)
		(property "Author" "Antmicro"
			(at 210.82 45.72 0)
			(effects
				(font
					(size 1.27 1.27)
					(thickness 0.15)
				)
				(justify left bottom)
				(hide yes)
			)
		)
		(property "License" "Apache-2.0"
			(at 208.28 45.72 0)
			(effects
				(font
					(size 1.27 1.27)
					(thickness 0.15)
				)
				(justify left bottom)
				(hide yes)
			)
		)
		(pin "1"
		)
		(pin "2"
		)
		(pin "3"
		)
		(instances
			(project "data-center-rdimm-ddr5-tester"
				(path ""
					(reference "Q22")
					(unit 1)
				)
			)
		)
	)
	(symbol
		(lib_id "antmicropower:GND")
		(at 350.52 116.84 0)
		(mirror y)
		(unit 1)
		(exclude_from_sim no)
		(in_bom yes)
		(on_board yes)
		(dnp no)
		(fields_autoplaced yes)
		(property "Reference" "#PWR0512"
			(at 350.52 123.19 0)
			(effects
				(font
					(size 1.27 1.27)
				)
				(hide yes)
			)
		)
		(property "Value" "GND"
			(at 352.425 121.285 0)
			(effects
				(font
					(size 1.27 1.27)
					(thickness 0.15)
				)
				(justify left bottom)
			)
		)
		(property "Footprint" ""
			(at 341.63 124.46 0)
			(effects
				(font
					(size 1.27 1.27)
					(thickness 0.15)
				)
				(justify left bottom)
				(hide yes)
			)
		)
		(property "Datasheet" ""
			(at 341.63 129.54 0)
			(effects
				(font
					(size 1.27 1.27)
					(thickness 0.15)
				)
				(justify left bottom)
				(hide yes)
			)
		)
		(property "Description" ""
			(at 350.52 116.84 0)
			(effects
				(font
					(size 1.27 1.27)
				)
				(hide yes)
			)
		)
		(property "Author" "Antmicro"
			(at 341.63 121.92 0)
			(effects
				(font
					(size 1.27 1.27)
					(thickness 0.15)
				)
				(justify left bottom)
				(hide yes)
			)
		)
		(property "License" "Apache-2.0"
			(at 341.63 124.46 0)
			(effects
				(font
					(size 1.27 1.27)
					(thickness 0.15)
				)
				(justify left bottom)
				(hide yes)
			)
		)
		(pin "1"
		)
		(instances
			(project "data-center-rdimm-ddr5-tester"
				(path ""
					(reference "#PWR0512")
					(unit 1)
				)
			)
		)
	)
	(symbol
		(lib_id "antmicropower:GND")
		(at 62.23 58.42 0)
		(mirror y)
		(unit 1)
		(exclude_from_sim no)
		(in_bom yes)
		(on_board yes)
		(dnp no)
		(fields_autoplaced yes)
		(property "Reference" "#PWR0269"
			(at 62.23 64.77 0)
			(effects
				(font
					(size 1.27 1.27)
				)
				(hide yes)
			)
		)
		(property "Value" "GND"
			(at 64.135 62.865 0)
			(effects
				(font
					(size 1.27 1.27)
					(thickness 0.15)
				)
				(justify left bottom)
			)
		)
		(property "Footprint" ""
			(at 53.34 66.04 0)
			(effects
				(font
					(size 1.27 1.27)
					(thickness 0.15)
				)
				(justify left bottom)
				(hide yes)
			)
		)
		(property "Datasheet" ""
			(at 53.34 71.12 0)
			(effects
				(font
					(size 1.27 1.27)
					(thickness 0.15)
				)
				(justify left bottom)
				(hide yes)
			)
		)
		(property "Description" ""
			(at 62.23 58.42 0)
			(effects
				(font
					(size 1.27 1.27)
				)
				(hide yes)
			)
		)
		(property "Author" "Antmicro"
			(at 53.34 63.5 0)
			(effects
				(font
					(size 1.27 1.27)
					(thickness 0.15)
				)
				(justify left bottom)
				(hide yes)
			)
		)
		(property "License" "Apache-2.0"
			(at 53.34 66.04 0)
			(effects
				(font
					(size 1.27 1.27)
					(thickness 0.15)
				)
				(justify left bottom)
				(hide yes)
			)
		)
		(pin "1"
		)
		(instances
			(project "data-center-rdimm-ddr5-tester"
				(path ""
					(reference "#PWR0269")
					(unit 1)
				)
			)
		)
	)
	(symbol
		(lib_id "antmicroResistors0402:R_0R_0402")
		(at 292.1 199.39 180)
		(unit 1)
		(exclude_from_sim no)
		(in_bom no)
		(on_board yes)
		(dnp yes)
		(property "Reference" "R175"
			(at 291.465 198.12 0)
			(effects
				(font
					(size 1.27 1.27)
				)
				(justify right)
			)
		)
		(property "Value" "R_0R_0402"
			(at 271.78 186.69 0)
			(effects
				(font
					(size 1.27 1.27)
					(thickness 0.15)
				)
				(justify left bottom)
				(hide yes)
			)
		)
		(property "Footprint" "antmicro-footprints:R_0402_1005Metric"
			(at 271.78 184.15 0)
			(effects
				(font
					(size 1.27 1.27)
					(thickness 0.15)
				)
				(justify left bottom)
				(hide yes)
			)
		)
		(property "Datasheet" "https://industrial.panasonic.com/cdbs/www-data/pdf/RDA0000/AOA0000C301.pdf"
			(at 271.78 181.61 0)
			(effects
				(font
					(size 1.27 1.27)
					(thickness 0.15)
				)
				(justify left bottom)
				(hide yes)
			)
		)
		(property "Description" ""
			(at 292.1 199.39 0)
			(effects
				(font
					(size 1.27 1.27)
				)
				(hide yes)
			)
		)
		(property "Manufacturer" "Panasonic"
			(at 271.78 176.53 0)
			(effects
				(font
					(size 1.27 1.27)
					(thickness 0.15)
				)
				(justify left bottom)
				(hide yes)
			)
		)
		(property "MPN" "ERJ2GE0R00X"
			(at 271.78 179.07 0)
			(effects
				(font
					(size 1.27 1.27)
					(thickness 0.15)
				)
				(justify left bottom)
				(hide yes)
			)
		)
		(property "Val" "0R"
			(at 284.48 198.12 0)
			(effects
				(font
					(size 1.27 1.27)
					(thickness 0.15)
				)
				(justify right)
			)
		)
		(property "License" "Apache-2.0"
			(at 271.78 173.99 0)
			(effects
				(font
					(size 1.27 1.27)
					(thickness 0.15)
				)
				(justify left bottom)
				(hide yes)
			)
		)
		(property "Author" "Antmicro"
			(at 271.78 171.45 0)
			(effects
				(font
					(size 1.27 1.27)
					(thickness 0.15)
				)
				(justify left bottom)
				(hide yes)
			)
		)
		(property "Tolerance" "~"
			(at 271.78 189.23 0)
			(effects
				(font
					(size 1.27 1.27)
				)
				(justify left bottom)
				(hide yes)
			)
		)
		(property "Current" "1A"
			(at 293.3699 196.85 90)
			(effects
				(font
					(size 1.27 1.27)
					(thickness 0.15)
				)
				(justify right)
				(hide yes)
			)
		)
		(pin "1"
		)
		(pin "2"
		)
		(instances
			(project "data-center-rdimm-ddr5-tester"
				(path ""
					(reference "R175")
					(unit 1)
				)
			)
		)
	)
	(symbol
		(lib_id "antmicroCapacitors0402:C_100n_0402")
		(at 256.54 68.58 270)
		(mirror x)
		(unit 1)
		(exclude_from_sim no)
		(in_bom yes)
		(on_board yes)
		(dnp no)
		(property "Reference" "C318"
			(at 259.08 64.7636 90)
			(effects
				(font
					(size 1.27 1.27)
					(thickness 0.15)
				)
				(justify left)
			)
		)
		(property "Value" "C_100n_0402"
			(at 246.38 48.26 0)
			(effects
				(font
					(size 1.27 1.27)
					(thickness 0.15)
				)
				(justify left bottom)
				(hide yes)
			)
		)
		(property "Footprint" "antmicro-footprints:C_0402_1005Metric"
			(at 243.84 48.26 0)
			(effects
				(font
					(size 1.27 1.27)
					(thickness 0.15)
				)
				(justify left bottom)
				(hide yes)
			)
		)
		(property "Datasheet" "https://www.murata.com/products/productdetail?partno=GRM155R61H104KE14%23"
			(at 241.3 48.26 0)
			(effects
				(font
					(size 1.27 1.27)
					(thickness 0.15)
				)
				(justify left bottom)
				(hide yes)
			)
		)
		(property "Description" ""
			(at 256.54 68.58 0)
			(effects
				(font
					(size 1.27 1.27)
				)
				(hide yes)
			)
		)
		(property "MPN" "GRM155R61H104KE14D"
			(at 238.76 48.26 0)
			(effects
				(font
					(size 1.27 1.27)
					(thickness 0.15)
				)
				(justify left bottom)
				(hide yes)
			)
		)
		(property "Manufacturer" "Murata"
			(at 236.22 48.26 0)
			(effects
				(font
					(size 1.27 1.27)
					(thickness 0.15)
				)
				(justify left bottom)
				(hide yes)
			)
		)
		(property "License" "Apache-2.0"
			(at 233.68 48.26 0)
			(effects
				(font
					(size 1.27 1.27)
					(thickness 0.15)
				)
				(justify left bottom)
				(hide yes)
			)
		)
		(property "Author" "Antmicro"
			(at 231.14 48.26 0)
			(effects
				(font
					(size 1.27 1.27)
					(thickness 0.15)
				)
				(justify left bottom)
				(hide yes)
			)
		)
		(property "Val" "100n"
			(at 259.08 67.3036 90)
			(effects
				(font
					(size 1.27 1.27)
					(thickness 0.15)
				)
				(justify left)
			)
		)
		(property "Voltage" "50V"
			(at 228.6 48.26 0)
			(effects
				(font
					(size 1.27 1.27)
				)
				(justify left bottom)
				(hide yes)
			)
		)
		(property "Dielectric" "X5R"
			(at 226.06 48.26 0)
			(effects
				(font
					(size 1.27 1.27)
				)
				(justify left bottom)
				(hide yes)
			)
		)
		(pin "1"
		)
		(pin "2"
		)
		(instances
			(project "data-center-rdimm-ddr5-tester"
				(path ""
					(reference "C318")
					(unit 1)
				)
			)
		)
	)
	(symbol
		(lib_id "antmicroResistors0402:R_4k7_0402")
		(at 347.98 80.01 90)
		(unit 1)
		(exclude_from_sim no)
		(in_bom yes)
		(on_board yes)
		(dnp no)
		(property "Reference" "R243"
			(at 349.25 76.2 90)
			(effects
				(font
					(size 1.27 1.27)
					(thickness 0.15)
				)
				(justify right)
			)
		)
		(property "Value" "R_4k7_0402"
			(at 360.68 59.69 0)
			(effects
				(font
					(size 1.27 1.27)
					(thickness 0.15)
				)
				(justify left bottom)
				(hide yes)
			)
		)
		(property "Footprint" "antmicro-footprints:R_0402_1005Metric"
			(at 363.22 59.69 0)
			(effects
				(font
					(size 1.27 1.27)
					(thickness 0.15)
				)
				(justify left bottom)
				(hide yes)
			)
		)
		(property "Datasheet" "https://www.bourns.com/docs/product-datasheets/cr.pdf"
			(at 365.76 59.69 0)
			(effects
				(font
					(size 1.27 1.27)
					(thickness 0.15)
				)
				(justify left bottom)
				(hide yes)
			)
		)
		(property "Description" ""
			(at 347.98 80.01 0)
			(effects
				(font
					(size 1.27 1.27)
				)
				(hide yes)
			)
		)
		(property "MPN" "CR0402-FX-4701GLF"
			(at 368.3 59.69 0)
			(effects
				(font
					(size 1.27 1.27)
					(thickness 0.15)
				)
				(justify left bottom)
				(hide yes)
			)
		)
		(property "Manufacturer" "Bourns"
			(at 370.84 59.69 0)
			(effects
				(font
					(size 1.27 1.27)
					(thickness 0.15)
				)
				(justify left bottom)
				(hide yes)
			)
		)
		(property "License" "Apache-2.0"
			(at 373.38 59.69 0)
			(effects
				(font
					(size 1.27 1.27)
					(thickness 0.15)
				)
				(justify left bottom)
				(hide yes)
			)
		)
		(property "Author" "Antmicro"
			(at 375.92 59.69 0)
			(effects
				(font
					(size 1.27 1.27)
					(thickness 0.15)
				)
				(justify left bottom)
				(hide yes)
			)
		)
		(property "Val" "4k7"
			(at 349.25 78.74 90)
			(effects
				(font
					(size 1.27 1.27)
					(thickness 0.15)
				)
				(justify right)
			)
		)
		(property "Tolerance" "1%"
			(at 358.14 59.69 0)
			(effects
				(font
					(size 1.27 1.27)
				)
				(justify left bottom)
				(hide yes)
			)
		)
		(pin "2"
		)
		(pin "1"
		)
		(instances
			(project "data-center-rdimm-ddr5-tester"
				(path ""
					(reference "R243")
					(unit 1)
				)
			)
		)
	)
	(symbol
		(lib_id "antmicropower:GND")
		(at 298.45 92.71 0)
		(unit 1)
		(exclude_from_sim no)
		(in_bom yes)
		(on_board yes)
		(dnp no)
		(fields_autoplaced yes)
		(property "Reference" "#PWR0518"
			(at 298.45 99.06 0)
			(effects
				(font
					(size 1.27 1.27)
				)
				(hide yes)
			)
		)
		(property "Value" "GND"
			(at 296.545 97.155 0)
			(effects
				(font
					(size 1.27 1.27)
					(thickness 0.15)
				)
				(justify left bottom)
			)
		)
		(property "Footprint" ""
			(at 307.34 100.33 0)
			(effects
				(font
					(size 1.27 1.27)
					(thickness 0.15)
				)
				(justify left bottom)
				(hide yes)
			)
		)
		(property "Datasheet" ""
			(at 307.34 105.41 0)
			(effects
				(font
					(size 1.27 1.27)
					(thickness 0.15)
				)
				(justify left bottom)
				(hide yes)
			)
		)
		(property "Description" ""
			(at 298.45 92.71 0)
			(effects
				(font
					(size 1.27 1.27)
				)
				(hide yes)
			)
		)
		(property "Author" "Antmicro"
			(at 307.34 97.79 0)
			(effects
				(font
					(size 1.27 1.27)
					(thickness 0.15)
				)
				(justify left bottom)
				(hide yes)
			)
		)
		(property "License" "Apache-2.0"
			(at 307.34 100.33 0)
			(effects
				(font
					(size 1.27 1.27)
					(thickness 0.15)
				)
				(justify left bottom)
				(hide yes)
			)
		)
		(pin "1"
		)
		(instances
			(project "data-center-rdimm-ddr5-tester"
				(path ""
					(reference "#PWR0518")
					(unit 1)
				)
			)
		)
	)
	(symbol
		(lib_id "antmicropower:+3V3_AON")
		(at 185.42 209.55 0)
		(mirror y)
		(unit 1)
		(exclude_from_sim no)
		(in_bom yes)
		(on_board yes)
		(dnp no)
		(fields_autoplaced yes)
		(property "Reference" "#PWR0440"
			(at 185.42 213.36 0)
			(effects
				(font
					(size 1.27 1.27)
				)
				(hide yes)
			)
		)
		(property "Value" "+3V3_AON"
			(at 185.42 203.835 0)
			(effects
				(font
					(size 1.27 1.27)
				)
			)
		)
		(property "Footprint" ""
			(at 185.42 209.55 0)
			(effects
				(font
					(size 1.27 1.27)
				)
				(hide yes)
			)
		)
		(property "Datasheet" ""
			(at 185.42 209.55 0)
			(effects
				(font
					(size 1.27 1.27)
				)
				(hide yes)
			)
		)
		(property "Description" ""
			(at 185.42 209.55 0)
			(effects
				(font
					(size 1.27 1.27)
				)
				(hide yes)
			)
		)
		(pin "1"
		)
		(instances
			(project "data-center-rdimm-ddr5-tester"
				(path ""
					(reference "#PWR0440")
					(unit 1)
				)
			)
		)
	)
	(symbol
		(lib_id "antmicroCapacitors0402:C_100n_0402")
		(at 185.42 194.31 270)
		(mirror x)
		(unit 1)
		(exclude_from_sim no)
		(in_bom yes)
		(on_board yes)
		(dnp no)
		(fields_autoplaced yes)
		(property "Reference" "C196"
			(at 182.88 190.4935 90)
			(effects
				(font
					(size 1.27 1.27)
				)
				(justify right)
			)
		)
		(property "Value" "C_100n_0402"
			(at 175.26 173.99 0)
			(effects
				(font
					(size 1.27 1.27)
					(thickness 0.15)
				)
				(justify left bottom)
				(hide yes)
			)
		)
		(property "Footprint" "antmicro-footprints:C_0402_1005Metric"
			(at 172.72 173.99 0)
			(effects
				(font
					(size 1.27 1.27)
					(thickness 0.15)
				)
				(justify left bottom)
				(hide yes)
			)
		)
		(property "Datasheet" "https://www.murata.com/products/productdetail?partno=GRM155R61H104KE14%23"
			(at 170.18 173.99 0)
			(effects
				(font
					(size 1.27 1.27)
					(thickness 0.15)
				)
				(justify left bottom)
				(hide yes)
			)
		)
		(property "Description" ""
			(at 185.42 194.31 0)
			(effects
				(font
					(size 1.27 1.27)
				)
				(hide yes)
			)
		)
		(property "Manufacturer" "Murata"
			(at 165.1 173.99 0)
			(effects
				(font
					(size 1.27 1.27)
					(thickness 0.15)
				)
				(justify left bottom)
				(hide yes)
			)
		)
		(property "MPN" "GRM155R61H104KE14D"
			(at 167.64 173.99 0)
			(effects
				(font
					(size 1.27 1.27)
					(thickness 0.15)
				)
				(justify left bottom)
				(hide yes)
			)
		)
		(property "Val" "100n"
			(at 182.88 193.0335 90)
			(effects
				(font
					(size 1.27 1.27)
					(thickness 0.15)
				)
				(justify right)
			)
		)
		(property "License" "Apache-2.0"
			(at 162.56 173.99 0)
			(effects
				(font
					(size 1.27 1.27)
					(thickness 0.15)
				)
				(justify left bottom)
				(hide yes)
			)
		)
		(property "Author" "Antmicro"
			(at 160.02 173.99 0)
			(effects
				(font
					(size 1.27 1.27)
					(thickness 0.15)
				)
				(justify left bottom)
				(hide yes)
			)
		)
		(property "Voltage" "50V"
			(at 157.48 173.99 0)
			(effects
				(font
					(size 1.27 1.27)
				)
				(justify left bottom)
				(hide yes)
			)
		)
		(property "Dielectric" "X5R"
			(at 154.94 173.99 0)
			(effects
				(font
					(size 1.27 1.27)
				)
				(justify left bottom)
				(hide yes)
			)
		)
		(pin "1"
		)
		(pin "2"
		)
		(instances
			(project "data-center-rdimm-ddr5-tester"
				(path ""
					(reference "C196")
					(unit 1)
				)
			)
		)
	)
	(symbol
		(lib_id "antmicroResistors0402:R_0R_0402")
		(at 367.03 58.42 270)
		(mirror x)
		(unit 1)
		(exclude_from_sim no)
		(in_bom yes)
		(on_board yes)
		(dnp no)
		(fields_autoplaced yes)
		(property "Reference" "R222"
			(at 368.681 55.0494 90)
			(effects
				(font
					(size 1.27 1.27)
					(thickness 0.15)
				)
				(justify left)
			)
		)
		(property "Value" "R_0R_0402"
			(at 354.33 38.1 0)
			(effects
				(font
					(size 1.27 1.27)
					(thickness 0.15)
				)
				(justify left bottom)
				(hide yes)
			)
		)
		(property "Footprint" "antmicro-footprints:R_0402_1005Metric"
			(at 351.79 38.1 0)
			(effects
				(font
					(size 1.27 1.27)
					(thickness 0.15)
				)
				(justify left bottom)
				(hide yes)
			)
		)
		(property "Datasheet" "https://industrial.panasonic.com/cdbs/www-data/pdf/RDA0000/AOA0000C301.pdf"
			(at 349.25 38.1 0)
			(effects
				(font
					(size 1.27 1.27)
					(thickness 0.15)
				)
				(justify left bottom)
				(hide yes)
			)
		)
		(property "Description" ""
			(at 367.03 58.42 0)
			(effects
				(font
					(size 1.27 1.27)
				)
				(hide yes)
			)
		)
		(property "MPN" "ERJ2GE0R00X"
			(at 346.71 38.1 0)
			(effects
				(font
					(size 1.27 1.27)
					(thickness 0.15)
				)
				(justify left bottom)
				(hide yes)
			)
		)
		(property "Manufacturer" "Panasonic"
			(at 344.17 38.1 0)
			(effects
				(font
					(size 1.27 1.27)
					(thickness 0.15)
				)
				(justify left bottom)
				(hide yes)
			)
		)
		(property "License" "Apache-2.0"
			(at 341.63 38.1 0)
			(effects
				(font
					(size 1.27 1.27)
					(thickness 0.15)
				)
				(justify left bottom)
				(hide yes)
			)
		)
		(property "Author" "Antmicro"
			(at 339.09 38.1 0)
			(effects
				(font
					(size 1.27 1.27)
					(thickness 0.15)
				)
				(justify left bottom)
				(hide yes)
			)
		)
		(property "Val" "0R"
			(at 368.681 57.5731 90)
			(effects
				(font
					(size 1.27 1.27)
					(thickness 0.15)
				)
				(justify left)
			)
		)
		(property "Tolerance" "~"
			(at 356.87 38.1 0)
			(effects
				(font
					(size 1.27 1.27)
				)
				(justify left bottom)
				(hide yes)
			)
		)
		(property "Current" "1A"
			(at 336.55 38.1 0)
			(effects
				(font
					(size 1.27 1.27)
					(thickness 0.15)
				)
				(justify left bottom)
				(hide yes)
			)
		)
		(pin "1"
		)
		(pin "2"
		)
		(instances
			(project "data-center-rdimm-ddr5-tester"
				(path ""
					(reference "R222")
					(unit 1)
				)
			)
		)
	)
	(symbol
		(lib_id "antmicroWire2BoardConnectors:JST_SH_1x4_BM04B-SRSS-TB-LF-SN")
		(at 370.84 80.01 0)
		(unit 1)
		(exclude_from_sim no)
		(in_bom yes)
		(on_board yes)
		(dnp no)
		(fields_autoplaced yes)
		(property "Reference" "J12"
			(at 377.825 83.82 0)
			(effects
				(font
					(size 1.27 1.27)
					(thickness 0.15)
				)
				(justify left)
			)
		)
		(property "Value" "JST_SH_1x4_BM04B-SRSS-TB-LF-SN"
			(at 391.16 87.63 0)
			(effects
				(font
					(size 1.27 1.27)
					(thickness 0.15)
				)
				(justify left bottom)
				(hide yes)
			)
		)
		(property "Footprint" "antmicro-footprints:Conn_JST_SH_1x4_BM04B-SRSS-TB-LF-SN"
			(at 391.16 90.17 0)
			(effects
				(font
					(size 1.27 1.27)
					(thickness 0.15)
				)
				(justify left bottom)
				(hide yes)
			)
		)
		(property "Datasheet" "https://www.jst-mfg.com/product/pdf/eng/eSH.pdf"
			(at 391.16 92.71 0)
			(effects
				(font
					(size 1.27 1.27)
					(thickness 0.15)
				)
				(justify left bottom)
				(hide yes)
			)
		)
		(property "Description" ""
			(at 370.84 80.01 0)
			(effects
				(font
					(size 1.27 1.27)
				)
				(hide yes)
			)
		)
		(property "MPN" "BM04B-SRSS-TB(LF)(SN) "
			(at 377.825 86.36 0)
			(effects
				(font
					(size 1.27 1.27)
					(thickness 0.15)
				)
				(justify left)
			)
		)
		(property "Manufacturer" "JST Automotive Connectors"
			(at 391.16 97.79 0)
			(effects
				(font
					(size 1.27 1.27)
					(thickness 0.15)
				)
				(justify left bottom)
				(hide yes)
			)
		)
		(property "Author" "Antmicro"
			(at 391.16 100.33 0)
			(effects
				(font
					(size 1.27 1.27)
					(thickness 0.15)
				)
				(justify left bottom)
				(hide yes)
			)
		)
		(property "License" "Apache-2.0"
			(at 391.16 102.87 0)
			(effects
				(font
					(size 1.27 1.27)
					(thickness 0.15)
				)
				(justify left bottom)
				(hide yes)
			)
		)
		(pin "1"
		)
		(pin "3"
		)
		(pin "MP"
		)
		(pin "4"
		)
		(pin "2"
		)
		(instances
			(project "data-center-rdimm-ddr5-tester"
				(path ""
					(reference "J12")
					(unit 1)
				)
			)
		)
	)
	(symbol
		(lib_id "antmicropower:+3V3")
		(at 367.03 50.8 0)
		(unit 1)
		(exclude_from_sim no)
		(in_bom yes)
		(on_board yes)
		(dnp no)
		(property "Reference" "#PWR0529"
			(at 382.27 50.8 0)
			(effects
				(font
					(size 1.27 1.27)
					(thickness 0.15)
				)
				(justify left bottom)
				(hide yes)
			)
		)
		(property "Value" "+3V3"
			(at 367.03 46.99 0)
			(effects
				(font
					(size 1.27 1.27)
					(thickness 0.15)
				)
			)
		)
		(property "Footprint" ""
			(at 382.27 58.42 0)
			(effects
				(font
					(size 1.27 1.27)
					(thickness 0.15)
				)
				(justify left bottom)
				(hide yes)
			)
		)
		(property "Datasheet" ""
			(at 382.27 60.96 0)
			(effects
				(font
					(size 1.27 1.27)
					(thickness 0.15)
				)
				(justify left bottom)
				(hide yes)
			)
		)
		(property "Description" ""
			(at 367.03 50.8 0)
			(effects
				(font
					(size 1.27 1.27)
				)
				(hide yes)
			)
		)
		(property "Author" "Antmicro"
			(at 382.27 53.34 0)
			(effects
				(font
					(size 1.27 1.27)
					(thickness 0.15)
				)
				(justify left bottom)
				(hide yes)
			)
		)
		(property "License" "Apache-2.0"
			(at 382.27 55.88 0)
			(effects
				(font
					(size 1.27 1.27)
					(thickness 0.15)
				)
				(justify left bottom)
				(hide yes)
			)
		)
		(pin "1"
		)
		(instances
			(project "data-center-rdimm-ddr5-tester"
				(path ""
					(reference "#PWR0529")
					(unit 1)
				)
			)
		)
	)
	(symbol
		(lib_id "antmicropower:+3V3")
		(at 311.15 50.8 0)
		(unit 1)
		(exclude_from_sim no)
		(in_bom yes)
		(on_board yes)
		(dnp no)
		(property "Reference" "#PWR0491"
			(at 326.39 50.8 0)
			(effects
				(font
					(size 1.27 1.27)
					(thickness 0.15)
				)
				(justify left bottom)
				(hide yes)
			)
		)
		(property "Value" "+3V3"
			(at 311.15 46.99 0)
			(effects
				(font
					(size 1.27 1.27)
					(thickness 0.15)
				)
			)
		)
		(property "Footprint" ""
			(at 326.39 58.42 0)
			(effects
				(font
					(size 1.27 1.27)
					(thickness 0.15)
				)
				(justify left bottom)
				(hide yes)
			)
		)
		(property "Datasheet" ""
			(at 326.39 60.96 0)
			(effects
				(font
					(size 1.27 1.27)
					(thickness 0.15)
				)
				(justify left bottom)
				(hide yes)
			)
		)
		(property "Description" ""
			(at 311.15 50.8 0)
			(effects
				(font
					(size 1.27 1.27)
				)
				(hide yes)
			)
		)
		(property "Author" "Antmicro"
			(at 326.39 53.34 0)
			(effects
				(font
					(size 1.27 1.27)
					(thickness 0.15)
				)
				(justify left bottom)
				(hide yes)
			)
		)
		(property "License" "Apache-2.0"
			(at 326.39 55.88 0)
			(effects
				(font
					(size 1.27 1.27)
					(thickness 0.15)
				)
				(justify left bottom)
				(hide yes)
			)
		)
		(pin "1"
		)
		(instances
			(project "data-center-rdimm-ddr5-tester"
				(path ""
					(reference "#PWR0491")
					(unit 1)
				)
			)
		)
	)
	(symbol
		(lib_id "antmicropower:GND")
		(at 185.42 220.98 0)
		(mirror y)
		(unit 1)
		(exclude_from_sim no)
		(in_bom yes)
		(on_board yes)
		(dnp no)
		(fields_autoplaced yes)
		(property "Reference" "#PWR0438"
			(at 185.42 227.33 0)
			(effects
				(font
					(size 1.27 1.27)
				)
				(hide yes)
			)
		)
		(property "Value" "GND"
			(at 187.325 225.425 0)
			(effects
				(font
					(size 1.27 1.27)
					(thickness 0.15)
				)
				(justify left bottom)
			)
		)
		(property "Footprint" ""
			(at 176.53 228.6 0)
			(effects
				(font
					(size 1.27 1.27)
					(thickness 0.15)
				)
				(justify left bottom)
				(hide yes)
			)
		)
		(property "Datasheet" ""
			(at 176.53 233.68 0)
			(effects
				(font
					(size 1.27 1.27)
					(thickness 0.15)
				)
				(justify left bottom)
				(hide yes)
			)
		)
		(property "Description" ""
			(at 185.42 220.98 0)
			(effects
				(font
					(size 1.27 1.27)
				)
				(hide yes)
			)
		)
		(property "Author" "Antmicro"
			(at 176.53 226.06 0)
			(effects
				(font
					(size 1.27 1.27)
					(thickness 0.15)
				)
				(justify left bottom)
				(hide yes)
			)
		)
		(property "License" "Apache-2.0"
			(at 176.53 228.6 0)
			(effects
				(font
					(size 1.27 1.27)
					(thickness 0.15)
				)
				(justify left bottom)
				(hide yes)
			)
		)
		(pin "1"
		)
		(instances
			(project "data-center-rdimm-ddr5-tester"
				(path ""
					(reference "#PWR0438")
					(unit 1)
				)
			)
		)
	)
	(symbol
		(lib_id "antmicroCapacitors0402:C_100n_0402")
		(at 381 72.39 90)
		(unit 1)
		(exclude_from_sim no)
		(in_bom yes)
		(on_board yes)
		(dnp no)
		(property "Reference" "C325"
			(at 378.46 68.5736 90)
			(effects
				(font
					(size 1.27 1.27)
					(thickness 0.15)
				)
				(justify left)
			)
		)
		(property "Value" "C_100n_0402"
			(at 391.16 52.07 0)
			(effects
				(font
					(size 1.27 1.27)
					(thickness 0.15)
				)
				(justify left bottom)
				(hide yes)
			)
		)
		(property "Footprint" "antmicro-footprints:C_0402_1005Metric"
			(at 393.7 52.07 0)
			(effects
				(font
					(size 1.27 1.27)
					(thickness 0.15)
				)
				(justify left bottom)
				(hide yes)
			)
		)
		(property "Datasheet" "https://www.murata.com/products/productdetail?partno=GRM155R61H104KE14%23"
			(at 396.24 52.07 0)
			(effects
				(font
					(size 1.27 1.27)
					(thickness 0.15)
				)
				(justify left bottom)
				(hide yes)
			)
		)
		(property "Description" ""
			(at 381 72.39 0)
			(effects
				(font
					(size 1.27 1.27)
				)
				(hide yes)
			)
		)
		(property "MPN" "GRM155R61H104KE14D"
			(at 398.78 52.07 0)
			(effects
				(font
					(size 1.27 1.27)
					(thickness 0.15)
				)
				(justify left bottom)
				(hide yes)
			)
		)
		(property "Manufacturer" "Murata"
			(at 401.32 52.07 0)
			(effects
				(font
					(size 1.27 1.27)
					(thickness 0.15)
				)
				(justify left bottom)
				(hide yes)
			)
		)
		(property "License" "Apache-2.0"
			(at 403.86 52.07 0)
			(effects
				(font
					(size 1.27 1.27)
					(thickness 0.15)
				)
				(justify left bottom)
				(hide yes)
			)
		)
		(property "Author" "Antmicro"
			(at 406.4 52.07 0)
			(effects
				(font
					(size 1.27 1.27)
					(thickness 0.15)
				)
				(justify left bottom)
				(hide yes)
			)
		)
		(property "Val" "100n"
			(at 378.46 71.1136 90)
			(effects
				(font
					(size 1.27 1.27)
					(thickness 0.15)
				)
				(justify left)
			)
		)
		(property "Voltage" "50V"
			(at 408.94 52.07 0)
			(effects
				(font
					(size 1.27 1.27)
				)
				(justify left bottom)
				(hide yes)
			)
		)
		(property "Dielectric" "X5R"
			(at 411.48 52.07 0)
			(effects
				(font
					(size 1.27 1.27)
				)
				(justify left bottom)
				(hide yes)
			)
		)
		(pin "1"
		)
		(pin "2"
		)
		(instances
			(project "data-center-rdimm-ddr5-tester"
				(path ""
					(reference "C325")
					(unit 1)
				)
			)
		)
	)
	(symbol
		(lib_id "antmicropower:GND")
		(at 256.54 68.58 0)
		(mirror y)
		(unit 1)
		(exclude_from_sim no)
		(in_bom yes)
		(on_board yes)
		(dnp no)
		(fields_autoplaced yes)
		(property "Reference" "#PWR0510"
			(at 256.54 74.93 0)
			(effects
				(font
					(size 1.27 1.27)
				)
				(hide yes)
			)
		)
		(property "Value" "GND"
			(at 258.445 73.025 0)
			(effects
				(font
					(size 1.27 1.27)
					(thickness 0.15)
				)
				(justify left bottom)
			)
		)
		(property "Footprint" ""
			(at 247.65 76.2 0)
			(effects
				(font
					(size 1.27 1.27)
					(thickness 0.15)
				)
				(justify left bottom)
				(hide yes)
			)
		)
		(property "Datasheet" ""
			(at 247.65 81.28 0)
			(effects
				(font
					(size 1.27 1.27)
					(thickness 0.15)
				)
				(justify left bottom)
				(hide yes)
			)
		)
		(property "Description" ""
			(at 256.54 68.58 0)
			(effects
				(font
					(size 1.27 1.27)
				)
				(hide yes)
			)
		)
		(property "Author" "Antmicro"
			(at 247.65 73.66 0)
			(effects
				(font
					(size 1.27 1.27)
					(thickness 0.15)
				)
				(justify left bottom)
				(hide yes)
			)
		)
		(property "License" "Apache-2.0"
			(at 247.65 76.2 0)
			(effects
				(font
					(size 1.27 1.27)
					(thickness 0.15)
				)
				(justify left bottom)
				(hide yes)
			)
		)
		(pin "1"
		)
		(instances
			(project "data-center-rdimm-ddr5-tester"
				(path ""
					(reference "#PWR0510")
					(unit 1)
				)
			)
		)
	)
	(symbol
		(lib_id "antmicropower:PWR_FLAG")
		(at 118.11 80.01 0)
		(unit 1)
		(exclude_from_sim no)
		(in_bom yes)
		(on_board yes)
		(dnp no)
		(fields_autoplaced yes)
		(property "Reference" "#FLG0107"
			(at 118.11 78.105 0)
			(effects
				(font
					(size 1.27 1.27)
				)
				(hide yes)
			)
		)
		(property "Value" "PWR_FLAG"
			(at 118.11 76.4342 0)
			(effects
				(font
					(size 1.27 1.27)
				)
			)
		)
		(property "Footprint" ""
			(at 118.11 80.01 0)
			(effects
				(font
					(size 1.27 1.27)
				)
				(hide yes)
			)
		)
		(property "Datasheet" ""
			(at 118.11 80.01 0)
			(effects
				(font
					(size 1.27 1.27)
				)
				(hide yes)
			)
		)
		(property "Description" ""
			(at 118.11 80.01 0)
			(effects
				(font
					(size 1.27 1.27)
				)
				(hide yes)
			)
		)
		(pin "1"
		)
		(instances
			(project "data-center-rdimm-ddr5-tester"
				(path ""
					(reference "#FLG0107")
					(unit 1)
				)
			)
		)
	)
	(symbol
		(lib_id "antmicroCapacitors0402:C_100n_0402")
		(at 49.53 53.34 90)
		(mirror x)
		(unit 1)
		(exclude_from_sim no)
		(in_bom yes)
		(on_board yes)
		(dnp no)
		(fields_autoplaced yes)
		(property "Reference" "C165"
			(at 52.07 54.6163 90)
			(effects
				(font
					(size 1.27 1.27)
				)
				(justify right)
			)
		)
		(property "Value" "C_100n_0402"
			(at 59.69 73.66 0)
			(effects
				(font
					(size 1.27 1.27)
					(thickness 0.15)
				)
				(justify left bottom)
				(hide yes)
			)
		)
		(property "Footprint" "antmicro-footprints:C_0402_1005Metric"
			(at 62.23 73.66 0)
			(effects
				(font
					(size 1.27 1.27)
					(thickness 0.15)
				)
				(justify left bottom)
				(hide yes)
			)
		)
		(property "Datasheet" "https://www.murata.com/products/productdetail?partno=GRM155R61H104KE14%23"
			(at 64.77 73.66 0)
			(effects
				(font
					(size 1.27 1.27)
					(thickness 0.15)
				)
				(justify left bottom)
				(hide yes)
			)
		)
		(property "Description" ""
			(at 49.53 53.34 0)
			(effects
				(font
					(size 1.27 1.27)
				)
				(hide yes)
			)
		)
		(property "Manufacturer" "Murata"
			(at 69.85 73.66 0)
			(effects
				(font
					(size 1.27 1.27)
					(thickness 0.15)
				)
				(justify left bottom)
				(hide yes)
			)
		)
		(property "MPN" "GRM155R61H104KE14D"
			(at 67.31 73.66 0)
			(effects
				(font
					(size 1.27 1.27)
					(thickness 0.15)
				)
				(justify left bottom)
				(hide yes)
			)
		)
		(property "Val" "100n"
			(at 52.07 57.7912 90)
			(effects
				(font
					(size 1.27 1.27)
					(thickness 0.15)
				)
				(justify right)
			)
		)
		(property "License" "Apache-2.0"
			(at 72.39 73.66 0)
			(effects
				(font
					(size 1.27 1.27)
					(thickness 0.15)
				)
				(justify left bottom)
				(hide yes)
			)
		)
		(property "Author" "Antmicro"
			(at 74.93 73.66 0)
			(effects
				(font
					(size 1.27 1.27)
					(thickness 0.15)
				)
				(justify left bottom)
				(hide yes)
			)
		)
		(property "Voltage" "50V"
			(at 77.47 73.66 0)
			(effects
				(font
					(size 1.27 1.27)
				)
				(justify left bottom)
				(hide yes)
			)
		)
		(property "Dielectric" "X5R"
			(at 80.01 73.66 0)
			(effects
				(font
					(size 1.27 1.27)
				)
				(justify left bottom)
				(hide yes)
			)
		)
		(pin "1"
		)
		(pin "2"
		)
		(instances
			(project "data-center-rdimm-ddr5-tester"
				(path ""
					(reference "C165")
					(unit 1)
				)
			)
		)
	)
	(symbol
		(lib_id "antmicroResistors0402:R_4k7_0402")
		(at 64.77 85.09 270)
		(unit 1)
		(exclude_from_sim no)
		(in_bom yes)
		(on_board yes)
		(dnp no)
		(property "Reference" "R122"
			(at 63.5 86.36 90)
			(effects
				(font
					(size 1.27 1.27)
				)
				(justify right)
			)
		)
		(property "Value" "R_4k7_0402"
			(at 52.07 105.41 0)
			(effects
				(font
					(size 1.27 1.27)
					(thickness 0.15)
				)
				(justify left bottom)
				(hide yes)
			)
		)
		(property "Footprint" "antmicro-footprints:R_0402_1005Metric"
			(at 49.53 105.41 0)
			(effects
				(font
					(size 1.27 1.27)
					(thickness 0.15)
				)
				(justify left bottom)
				(hide yes)
			)
		)
		(property "Datasheet" "https://www.bourns.com/docs/product-datasheets/cr.pdf"
			(at 46.99 105.41 0)
			(effects
				(font
					(size 1.27 1.27)
					(thickness 0.15)
				)
				(justify left bottom)
				(hide yes)
			)
		)
		(property "Description" ""
			(at 64.77 85.09 0)
			(effects
				(font
					(size 1.27 1.27)
				)
				(hide yes)
			)
		)
		(property "Manufacturer" "Bourns"
			(at 41.91 105.41 0)
			(effects
				(font
					(size 1.27 1.27)
					(thickness 0.15)
				)
				(justify left bottom)
				(hide yes)
			)
		)
		(property "MPN" "CR0402-FX-4701GLF"
			(at 44.45 105.41 0)
			(effects
				(font
					(size 1.27 1.27)
					(thickness 0.15)
				)
				(justify left bottom)
				(hide yes)
			)
		)
		(property "Val" "4k7"
			(at 63.5 89.535 90)
			(effects
				(font
					(size 1.27 1.27)
					(thickness 0.15)
				)
				(justify right)
			)
		)
		(property "License" "Apache-2.0"
			(at 39.37 105.41 0)
			(effects
				(font
					(size 1.27 1.27)
					(thickness 0.15)
				)
				(justify left bottom)
				(hide yes)
			)
		)
		(property "Author" "Antmicro"
			(at 36.83 105.41 0)
			(effects
				(font
					(size 1.27 1.27)
					(thickness 0.15)
				)
				(justify left bottom)
				(hide yes)
			)
		)
		(property "Tolerance" "1%"
			(at 54.61 105.41 0)
			(effects
				(font
					(size 1.27 1.27)
				)
				(justify left bottom)
				(hide yes)
			)
		)
		(pin "1"
		)
		(pin "2"
		)
		(instances
			(project "data-center-rdimm-ddr5-tester"
				(path ""
					(reference "R122")
					(unit 1)
				)
			)
		)
	)
	(symbol
		(lib_id "antmicroResistors0402:R_0R_0402")
		(at 303.53 57.15 270)
		(mirror x)
		(unit 1)
		(exclude_from_sim no)
		(in_bom yes)
		(on_board yes)
		(dnp no)
		(fields_autoplaced yes)
		(property "Reference" "R15"
			(at 305.181 53.7794 90)
			(effects
				(font
					(size 1.27 1.27)
					(thickness 0.15)
				)
				(justify left)
			)
		)
		(property "Value" "R_0R_0402"
			(at 290.83 36.83 0)
			(effects
				(font
					(size 1.27 1.27)
					(thickness 0.15)
				)
				(justify left bottom)
				(hide yes)
			)
		)
		(property "Footprint" "antmicro-footprints:R_0402_1005Metric"
			(at 288.29 36.83 0)
			(effects
				(font
					(size 1.27 1.27)
					(thickness 0.15)
				)
				(justify left bottom)
				(hide yes)
			)
		)
		(property "Datasheet" "https://industrial.panasonic.com/cdbs/www-data/pdf/RDA0000/AOA0000C301.pdf"
			(at 285.75 36.83 0)
			(effects
				(font
					(size 1.27 1.27)
					(thickness 0.15)
				)
				(justify left bottom)
				(hide yes)
			)
		)
		(property "Description" ""
			(at 303.53 57.15 0)
			(effects
				(font
					(size 1.27 1.27)
				)
				(hide yes)
			)
		)
		(property "MPN" "ERJ2GE0R00X"
			(at 283.21 36.83 0)
			(effects
				(font
					(size 1.27 1.27)
					(thickness 0.15)
				)
				(justify left bottom)
				(hide yes)
			)
		)
		(property "Manufacturer" "Panasonic"
			(at 280.67 36.83 0)
			(effects
				(font
					(size 1.27 1.27)
					(thickness 0.15)
				)
				(justify left bottom)
				(hide yes)
			)
		)
		(property "License" "Apache-2.0"
			(at 278.13 36.83 0)
			(effects
				(font
					(size 1.27 1.27)
					(thickness 0.15)
				)
				(justify left bottom)
				(hide yes)
			)
		)
		(property "Author" "Antmicro"
			(at 275.59 36.83 0)
			(effects
				(font
					(size 1.27 1.27)
					(thickness 0.15)
				)
				(justify left bottom)
				(hide yes)
			)
		)
		(property "Val" "0R"
			(at 305.181 56.3031 90)
			(effects
				(font
					(size 1.27 1.27)
					(thickness 0.15)
				)
				(justify left)
			)
		)
		(property "Tolerance" "~"
			(at 293.37 36.83 0)
			(effects
				(font
					(size 1.27 1.27)
				)
				(justify left bottom)
				(hide yes)
			)
		)
		(property "Current" "1A"
			(at 273.05 36.83 0)
			(effects
				(font
					(size 1.27 1.27)
					(thickness 0.15)
				)
				(justify left bottom)
				(hide yes)
			)
		)
		(pin "1"
		)
		(pin "2"
		)
		(instances
			(project "data-center-rdimm-ddr5-tester"
				(path ""
					(reference "R15")
					(unit 1)
				)
			)
		)
	)
	(symbol
		(lib_id "antmicropower:GND")
		(at 381 73.66 0)
		(mirror y)
		(unit 1)
		(exclude_from_sim no)
		(in_bom yes)
		(on_board yes)
		(dnp no)
		(fields_autoplaced yes)
		(property "Reference" "#PWR0528"
			(at 381 80.01 0)
			(effects
				(font
					(size 1.27 1.27)
				)
				(hide yes)
			)
		)
		(property "Value" "GND"
			(at 382.905 78.105 0)
			(effects
				(font
					(size 1.27 1.27)
					(thickness 0.15)
				)
				(justify left bottom)
			)
		)
		(property "Footprint" ""
			(at 372.11 81.28 0)
			(effects
				(font
					(size 1.27 1.27)
					(thickness 0.15)
				)
				(justify left bottom)
				(hide yes)
			)
		)
		(property "Datasheet" ""
			(at 372.11 86.36 0)
			(effects
				(font
					(size 1.27 1.27)
					(thickness 0.15)
				)
				(justify left bottom)
				(hide yes)
			)
		)
		(property "Description" ""
			(at 381 73.66 0)
			(effects
				(font
					(size 1.27 1.27)
				)
				(hide yes)
			)
		)
		(property "Author" "Antmicro"
			(at 372.11 78.74 0)
			(effects
				(font
					(size 1.27 1.27)
					(thickness 0.15)
				)
				(justify left bottom)
				(hide yes)
			)
		)
		(property "License" "Apache-2.0"
			(at 372.11 81.28 0)
			(effects
				(font
					(size 1.27 1.27)
					(thickness 0.15)
				)
				(justify left bottom)
				(hide yes)
			)
		)
		(pin "1"
		)
		(instances
			(project "data-center-rdimm-ddr5-tester"
				(path ""
					(reference "#PWR0528")
					(unit 1)
				)
			)
		)
	)
	(symbol
		(lib_id "antmicropower:GND")
		(at 49.53 58.42 0)
		(mirror y)
		(unit 1)
		(exclude_from_sim no)
		(in_bom yes)
		(on_board yes)
		(dnp no)
		(fields_autoplaced yes)
		(property "Reference" "#PWR0268"
			(at 49.53 64.77 0)
			(effects
				(font
					(size 1.27 1.27)
				)
				(hide yes)
			)
		)
		(property "Value" "GND"
			(at 51.435 62.865 0)
			(effects
				(font
					(size 1.27 1.27)
					(thickness 0.15)
				)
				(justify left bottom)
			)
		)
		(property "Footprint" ""
			(at 40.64 66.04 0)
			(effects
				(font
					(size 1.27 1.27)
					(thickness 0.15)
				)
				(justify left bottom)
				(hide yes)
			)
		)
		(property "Datasheet" ""
			(at 40.64 71.12 0)
			(effects
				(font
					(size 1.27 1.27)
					(thickness 0.15)
				)
				(justify left bottom)
				(hide yes)
			)
		)
		(property "Description" ""
			(at 49.53 58.42 0)
			(effects
				(font
					(size 1.27 1.27)
				)
				(hide yes)
			)
		)
		(property "Author" "Antmicro"
			(at 40.64 63.5 0)
			(effects
				(font
					(size 1.27 1.27)
					(thickness 0.15)
				)
				(justify left bottom)
				(hide yes)
			)
		)
		(property "License" "Apache-2.0"
			(at 40.64 66.04 0)
			(effects
				(font
					(size 1.27 1.27)
					(thickness 0.15)
				)
				(justify left bottom)
				(hide yes)
			)
		)
		(pin "1"
		)
		(instances
			(project "data-center-rdimm-ddr5-tester"
				(path ""
					(reference "#PWR0268")
					(unit 1)
				)
			)
		)
	)
	(symbol
		(lib_id "antmicroResistors0402:R_200k_0402")
		(at 269.24 67.31 270)
		(mirror x)
		(unit 1)
		(exclude_from_sim no)
		(in_bom yes)
		(on_board yes)
		(dnp no)
		(fields_autoplaced yes)
		(property "Reference" "R75"
			(at 271.78 63.5 90)
			(effects
				(font
					(size 1.27 1.27)
					(thickness 0.15)
				)
				(justify left)
			)
		)
		(property "Value" "R_200k_0402"
			(at 256.54 46.99 0)
			(effects
				(font
					(size 1.27 1.27)
					(thickness 0.15)
				)
				(justify left bottom)
				(hide yes)
			)
		)
		(property "Footprint" "antmicro-footprints:R_0402_1005Metric"
			(at 254 46.99 0)
			(effects
				(font
					(size 1.27 1.27)
					(thickness 0.15)
				)
				(justify left bottom)
				(hide yes)
			)
		)
		(property "Datasheet" "https://www.bourns.com/docs/product-datasheets/cr.pdf"
			(at 251.46 46.99 0)
			(effects
				(font
					(size 1.27 1.27)
					(thickness 0.15)
				)
				(justify left bottom)
				(hide yes)
			)
		)
		(property "Description" ""
			(at 269.24 67.31 0)
			(effects
				(font
					(size 1.27 1.27)
				)
				(hide yes)
			)
		)
		(property "MPN" "CR0402-FX-2003GLF"
			(at 248.92 46.99 0)
			(effects
				(font
					(size 1.27 1.27)
					(thickness 0.15)
				)
				(justify left bottom)
				(hide yes)
			)
		)
		(property "Manufacturer" "Bourns"
			(at 246.38 46.99 0)
			(effects
				(font
					(size 1.27 1.27)
					(thickness 0.15)
				)
				(justify left bottom)
				(hide yes)
			)
		)
		(property "License" "Apache-2.0"
			(at 243.84 46.99 0)
			(effects
				(font
					(size 1.27 1.27)
					(thickness 0.15)
				)
				(justify left bottom)
				(hide yes)
			)
		)
		(property "Author" "Antmicro"
			(at 241.3 46.99 0)
			(effects
				(font
					(size 1.27 1.27)
					(thickness 0.15)
				)
				(justify left bottom)
				(hide yes)
			)
		)
		(property "Val" "200k"
			(at 271.78 66.04 90)
			(effects
				(font
					(size 1.27 1.27)
					(thickness 0.15)
				)
				(justify left)
			)
		)
		(property "Tolerance" "1%"
			(at 259.08 46.99 0)
			(effects
				(font
					(size 1.27 1.27)
				)
				(justify left bottom)
				(hide yes)
			)
		)
		(pin "1"
		)
		(pin "2"
		)
		(instances
			(project "data-center-rdimm-ddr5-tester"
				(path ""
					(reference "R75")
					(unit 1)
				)
			)
		)
	)
	(symbol
		(lib_id "antmicroResistors0402:R_0R_0402")
		(at 292.1 210.82 180)
		(unit 1)
		(exclude_from_sim no)
		(in_bom no)
		(on_board yes)
		(dnp yes)
		(property "Reference" "R179"
			(at 291.465 209.55 0)
			(effects
				(font
					(size 1.27 1.27)
				)
				(justify right)
			)
		)
		(property "Value" "R_0R_0402"
			(at 271.78 198.12 0)
			(effects
				(font
					(size 1.27 1.27)
					(thickness 0.15)
				)
				(justify left bottom)
				(hide yes)
			)
		)
		(property "Footprint" "antmicro-footprints:R_0402_1005Metric"
			(at 271.78 195.58 0)
			(effects
				(font
					(size 1.27 1.27)
					(thickness 0.15)
				)
				(justify left bottom)
				(hide yes)
			)
		)
		(property "Datasheet" "https://industrial.panasonic.com/cdbs/www-data/pdf/RDA0000/AOA0000C301.pdf"
			(at 271.78 193.04 0)
			(effects
				(font
					(size 1.27 1.27)
					(thickness 0.15)
				)
				(justify left bottom)
				(hide yes)
			)
		)
		(property "Description" ""
			(at 292.1 210.82 0)
			(effects
				(font
					(size 1.27 1.27)
				)
				(hide yes)
			)
		)
		(property "Manufacturer" "Panasonic"
			(at 271.78 187.96 0)
			(effects
				(font
					(size 1.27 1.27)
					(thickness 0.15)
				)
				(justify left bottom)
				(hide yes)
			)
		)
		(property "MPN" "ERJ2GE0R00X"
			(at 271.78 190.5 0)
			(effects
				(font
					(size 1.27 1.27)
					(thickness 0.15)
				)
				(justify left bottom)
				(hide yes)
			)
		)
		(property "Val" "0R"
			(at 284.48 209.55 0)
			(effects
				(font
					(size 1.27 1.27)
					(thickness 0.15)
				)
				(justify right)
			)
		)
		(property "License" "Apache-2.0"
			(at 271.78 185.42 0)
			(effects
				(font
					(size 1.27 1.27)
					(thickness 0.15)
				)
				(justify left bottom)
				(hide yes)
			)
		)
		(property "Author" "Antmicro"
			(at 271.78 182.88 0)
			(effects
				(font
					(size 1.27 1.27)
					(thickness 0.15)
				)
				(justify left bottom)
				(hide yes)
			)
		)
		(property "Tolerance" "~"
			(at 271.78 200.66 0)
			(effects
				(font
					(size 1.27 1.27)
				)
				(justify left bottom)
				(hide yes)
			)
		)
		(property "Current" "1A"
			(at 293.3699 208.28 90)
			(effects
				(font
					(size 1.27 1.27)
					(thickness 0.15)
				)
				(justify right)
				(hide yes)
			)
		)
		(pin "1"
		)
		(pin "2"
		)
		(instances
			(project "data-center-rdimm-ddr5-tester"
				(path ""
					(reference "R179")
					(unit 1)
				)
			)
		)
	)
	(symbol
		(lib_id "antmicroResistors0402:R_0R_0402")
		(at 292.1 205.74 180)
		(unit 1)
		(exclude_from_sim no)
		(in_bom no)
		(on_board yes)
		(dnp yes)
		(property "Reference" "R177"
			(at 291.465 204.47 0)
			(effects
				(font
					(size 1.27 1.27)
				)
				(justify right)
			)
		)
		(property "Value" "R_0R_0402"
			(at 271.78 193.04 0)
			(effects
				(font
					(size 1.27 1.27)
					(thickness 0.15)
				)
				(justify left bottom)
				(hide yes)
			)
		)
		(property "Footprint" "antmicro-footprints:R_0402_1005Metric"
			(at 271.78 190.5 0)
			(effects
				(font
					(size 1.27 1.27)
					(thickness 0.15)
				)
				(justify left bottom)
				(hide yes)
			)
		)
		(property "Datasheet" "https://industrial.panasonic.com/cdbs/www-data/pdf/RDA0000/AOA0000C301.pdf"
			(at 271.78 187.96 0)
			(effects
				(font
					(size 1.27 1.27)
					(thickness 0.15)
				)
				(justify left bottom)
				(hide yes)
			)
		)
		(property "Description" ""
			(at 292.1 205.74 0)
			(effects
				(font
					(size 1.27 1.27)
				)
				(hide yes)
			)
		)
		(property "Manufacturer" "Panasonic"
			(at 271.78 182.88 0)
			(effects
				(font
					(size 1.27 1.27)
					(thickness 0.15)
				)
				(justify left bottom)
				(hide yes)
			)
		)
		(property "MPN" "ERJ2GE0R00X"
			(at 271.78 185.42 0)
			(effects
				(font
					(size 1.27 1.27)
					(thickness 0.15)
				)
				(justify left bottom)
				(hide yes)
			)
		)
		(property "Val" "0R"
			(at 284.48 204.47 0)
			(effects
				(font
					(size 1.27 1.27)
					(thickness 0.15)
				)
				(justify right)
			)
		)
		(property "License" "Apache-2.0"
			(at 271.78 180.34 0)
			(effects
				(font
					(size 1.27 1.27)
					(thickness 0.15)
				)
				(justify left bottom)
				(hide yes)
			)
		)
		(property "Author" "Antmicro"
			(at 271.78 177.8 0)
			(effects
				(font
					(size 1.27 1.27)
					(thickness 0.15)
				)
				(justify left bottom)
				(hide yes)
			)
		)
		(property "Tolerance" "~"
			(at 271.78 195.58 0)
			(effects
				(font
					(size 1.27 1.27)
				)
				(justify left bottom)
				(hide yes)
			)
		)
		(property "Current" "1A"
			(at 293.3699 203.2 90)
			(effects
				(font
					(size 1.27 1.27)
					(thickness 0.15)
				)
				(justify right)
				(hide yes)
			)
		)
		(pin "1"
		)
		(pin "2"
		)
		(instances
			(project "data-center-rdimm-ddr5-tester"
				(path ""
					(reference "R177")
					(unit 1)
				)
			)
		)
	)
	(symbol
		(lib_id "antmicroResistors0402:R_47k_0402")
		(at 222.25 68.58 90)
		(unit 1)
		(exclude_from_sim no)
		(in_bom yes)
		(on_board yes)
		(dnp no)
		(fields_autoplaced yes)
		(property "Reference" "R223"
			(at 219.71 64.77 90)
			(effects
				(font
					(size 1.27 1.27)
					(thickness 0.15)
				)
				(justify left)
			)
		)
		(property "Value" "R_47k_0402"
			(at 234.95 48.26 0)
			(effects
				(font
					(size 1.27 1.27)
					(thickness 0.15)
				)
				(justify left bottom)
				(hide yes)
			)
		)
		(property "Footprint" "antmicro-footprints:R_0402_1005Metric"
			(at 237.49 48.26 0)
			(effects
				(font
					(size 1.27 1.27)
					(thickness 0.15)
				)
				(justify left bottom)
				(hide yes)
			)
		)
		(property "Datasheet" "https://www.bourns.com/docs/product-datasheets/cr.pdf"
			(at 240.03 48.26 0)
			(effects
				(font
					(size 1.27 1.27)
					(thickness 0.15)
				)
				(justify left bottom)
				(hide yes)
			)
		)
		(property "Description" ""
			(at 222.25 68.58 0)
			(effects
				(font
					(size 1.27 1.27)
				)
				(hide yes)
			)
		)
		(property "MPN" "CR0402-FX-4702GLF"
			(at 242.57 48.26 0)
			(effects
				(font
					(size 1.27 1.27)
					(thickness 0.15)
				)
				(justify left bottom)
				(hide yes)
			)
		)
		(property "Manufacturer" "Bourns"
			(at 245.11 48.26 0)
			(effects
				(font
					(size 1.27 1.27)
					(thickness 0.15)
				)
				(justify left bottom)
				(hide yes)
			)
		)
		(property "License" "Apache-2.0"
			(at 247.65 48.26 0)
			(effects
				(font
					(size 1.27 1.27)
					(thickness 0.15)
				)
				(justify left bottom)
				(hide yes)
			)
		)
		(property "Author" "Antmicro"
			(at 250.19 48.26 0)
			(effects
				(font
					(size 1.27 1.27)
					(thickness 0.15)
				)
				(justify left bottom)
				(hide yes)
			)
		)
		(property "Val" "47k"
			(at 219.71 67.31 90)
			(effects
				(font
					(size 1.27 1.27)
					(thickness 0.15)
				)
				(justify left)
			)
		)
		(property "Tolerance" "1%"
			(at 232.41 48.26 0)
			(effects
				(font
					(size 1.27 1.27)
				)
				(justify left bottom)
				(hide yes)
			)
		)
		(pin "2"
		)
		(pin "1"
		)
		(instances
			(project "data-center-rdimm-ddr5-tester"
				(path ""
					(reference "R223")
					(unit 1)
				)
			)
		)
	)
	(symbol
		(lib_id "antmicroResistors0402:R_0R_0402")
		(at 311.15 57.15 270)
		(mirror x)
		(unit 1)
		(exclude_from_sim no)
		(in_bom no)
		(on_board yes)
		(dnp yes)
		(fields_autoplaced yes)
		(property "Reference" "R96"
			(at 312.801 53.7794 90)
			(effects
				(font
					(size 1.27 1.27)
					(thickness 0.15)
				)
				(justify left)
			)
		)
		(property "Value" "R_0R_0402"
			(at 298.45 36.83 0)
			(effects
				(font
					(size 1.27 1.27)
					(thickness 0.15)
				)
				(justify left bottom)
				(hide yes)
			)
		)
		(property "Footprint" "antmicro-footprints:R_0402_1005Metric"
			(at 295.91 36.83 0)
			(effects
				(font
					(size 1.27 1.27)
					(thickness 0.15)
				)
				(justify left bottom)
				(hide yes)
			)
		)
		(property "Datasheet" "https://industrial.panasonic.com/cdbs/www-data/pdf/RDA0000/AOA0000C301.pdf"
			(at 293.37 36.83 0)
			(effects
				(font
					(size 1.27 1.27)
					(thickness 0.15)
				)
				(justify left bottom)
				(hide yes)
			)
		)
		(property "Description" ""
			(at 311.15 57.15 0)
			(effects
				(font
					(size 1.27 1.27)
				)
				(hide yes)
			)
		)
		(property "MPN" "ERJ2GE0R00X"
			(at 290.83 36.83 0)
			(effects
				(font
					(size 1.27 1.27)
					(thickness 0.15)
				)
				(justify left bottom)
				(hide yes)
			)
		)
		(property "Manufacturer" "Panasonic"
			(at 288.29 36.83 0)
			(effects
				(font
					(size 1.27 1.27)
					(thickness 0.15)
				)
				(justify left bottom)
				(hide yes)
			)
		)
		(property "License" "Apache-2.0"
			(at 285.75 36.83 0)
			(effects
				(font
					(size 1.27 1.27)
					(thickness 0.15)
				)
				(justify left bottom)
				(hide yes)
			)
		)
		(property "Author" "Antmicro"
			(at 283.21 36.83 0)
			(effects
				(font
					(size 1.27 1.27)
					(thickness 0.15)
				)
				(justify left bottom)
				(hide yes)
			)
		)
		(property "Val" "0R"
			(at 312.801 56.3031 90)
			(effects
				(font
					(size 1.27 1.27)
					(thickness 0.15)
				)
				(justify left)
			)
		)
		(property "Tolerance" "~"
			(at 300.99 36.83 0)
			(effects
				(font
					(size 1.27 1.27)
				)
				(justify left bottom)
				(hide yes)
			)
		)
		(property "Current" "1A"
			(at 280.67 36.83 0)
			(effects
				(font
					(size 1.27 1.27)
					(thickness 0.15)
				)
				(justify left bottom)
				(hide yes)
			)
		)
		(pin "1"
		)
		(pin "2"
		)
		(instances
			(project "data-center-rdimm-ddr5-tester"
				(path ""
					(reference "R96")
					(unit 1)
				)
			)
		)
	)
	(symbol
		(lib_id "antmicropower:GND")
		(at 171.45 224.79 0)
		(unit 1)
		(exclude_from_sim no)
		(in_bom yes)
		(on_board yes)
		(dnp no)
		(property "Reference" "#PWR0439"
			(at 171.45 231.14 0)
			(effects
				(font
					(size 1.27 1.27)
				)
				(hide yes)
			)
		)
		(property "Value" "GND"
			(at 169.545 229.235 0)
			(effects
				(font
					(size 1.27 1.27)
					(thickness 0.15)
				)
				(justify left bottom)
			)
		)
		(property "Footprint" ""
			(at 180.34 232.41 0)
			(effects
				(font
					(size 1.27 1.27)
					(thickness 0.15)
				)
				(justify left bottom)
				(hide yes)
			)
		)
		(property "Datasheet" ""
			(at 180.34 237.49 0)
			(effects
				(font
					(size 1.27 1.27)
					(thickness 0.15)
				)
				(justify left bottom)
				(hide yes)
			)
		)
		(property "Description" ""
			(at 171.45 224.79 0)
			(effects
				(font
					(size 1.27 1.27)
				)
				(hide yes)
			)
		)
		(property "Author" "Antmicro"
			(at 180.34 229.87 0)
			(effects
				(font
					(size 1.27 1.27)
					(thickness 0.15)
				)
				(justify left bottom)
				(hide yes)
			)
		)
		(property "License" "Apache-2.0"
			(at 180.34 232.41 0)
			(effects
				(font
					(size 1.27 1.27)
					(thickness 0.15)
				)
				(justify left bottom)
				(hide yes)
			)
		)
		(pin "1"
		)
		(instances
			(project "data-center-rdimm-ddr5-tester"
				(path ""
					(reference "#PWR0439")
					(unit 1)
				)
			)
		)
	)
	(symbol
		(lib_id "antmicroResistors0402:R_0R_0402")
		(at 123.19 52.07 90)
		(mirror x)
		(unit 1)
		(exclude_from_sim no)
		(in_bom no)
		(on_board yes)
		(dnp yes)
		(property "Reference" "R126"
			(at 121.285 53.975 90)
			(effects
				(font
					(size 1.27 1.27)
					(thickness 0.15)
				)
				(justify left)
			)
		)
		(property "Value" "R_0R_0402"
			(at 135.89 72.39 0)
			(effects
				(font
					(size 1.27 1.27)
					(thickness 0.15)
				)
				(justify left bottom)
				(hide yes)
			)
		)
		(property "Footprint" "antmicro-footprints:R_0402_1005Metric"
			(at 138.43 72.39 0)
			(effects
				(font
					(size 1.27 1.27)
					(thickness 0.15)
				)
				(justify left bottom)
				(hide yes)
			)
		)
		(property "Datasheet" "https://industrial.panasonic.com/cdbs/www-data/pdf/RDA0000/AOA0000C301.pdf"
			(at 140.97 72.39 0)
			(effects
				(font
					(size 1.27 1.27)
					(thickness 0.15)
				)
				(justify left bottom)
				(hide yes)
			)
		)
		(property "Description" ""
			(at 123.19 52.07 0)
			(effects
				(font
					(size 1.27 1.27)
				)
				(hide yes)
			)
		)
		(property "MPN" "ERJ2GE0R00X"
			(at 143.51 72.39 0)
			(effects
				(font
					(size 1.27 1.27)
					(thickness 0.15)
				)
				(justify left bottom)
				(hide yes)
			)
		)
		(property "Manufacturer" "Panasonic"
			(at 146.05 72.39 0)
			(effects
				(font
					(size 1.27 1.27)
					(thickness 0.15)
				)
				(justify left bottom)
				(hide yes)
			)
		)
		(property "License" "Apache-2.0"
			(at 148.59 72.39 0)
			(effects
				(font
					(size 1.27 1.27)
					(thickness 0.15)
				)
				(justify left bottom)
				(hide yes)
			)
		)
		(property "Author" "Antmicro"
			(at 151.13 72.39 0)
			(effects
				(font
					(size 1.27 1.27)
					(thickness 0.15)
				)
				(justify left bottom)
				(hide yes)
			)
		)
		(property "Val" "0R"
			(at 121.285 56.4987 90)
			(effects
				(font
					(size 1.27 1.27)
					(thickness 0.15)
				)
				(justify left)
			)
		)
		(property "Tolerance" "~"
			(at 133.35 72.39 0)
			(effects
				(font
					(size 1.27 1.27)
				)
				(justify left bottom)
				(hide yes)
			)
		)
		(property "Current" "1A"
			(at 153.67 72.39 0)
			(effects
				(font
					(size 1.27 1.27)
					(thickness 0.15)
				)
				(justify left bottom)
				(hide yes)
			)
		)
		(pin "1"
		)
		(pin "2"
		)
		(instances
			(project "data-center-rdimm-ddr5-tester"
				(path ""
					(reference "R126")
					(unit 1)
				)
			)
		)
	)
	(symbol
		(lib_id "antmicroResistors0402:R_4k7_0402")
		(at 123.19 177.8 270)
		(unit 1)
		(exclude_from_sim no)
		(in_bom yes)
		(on_board yes)
		(dnp no)
		(property "Reference" "R159"
			(at 124.46 179.07 90)
			(effects
				(font
					(size 1.27 1.27)
				)
				(justify left)
			)
		)
		(property "Value" "R_4k7_0402"
			(at 110.49 198.12 0)
			(effects
				(font
					(size 1.27 1.27)
					(thickness 0.15)
				)
				(justify left bottom)
				(hide yes)
			)
		)
		(property "Footprint" "antmicro-footprints:R_0402_1005Metric"
			(at 107.95 198.12 0)
			(effects
				(font
					(size 1.27 1.27)
					(thickness 0.15)
				)
				(justify left bottom)
				(hide yes)
			)
		)
		(property "Datasheet" "https://www.bourns.com/docs/product-datasheets/cr.pdf"
			(at 105.41 198.12 0)
			(effects
				(font
					(size 1.27 1.27)
					(thickness 0.15)
				)
				(justify left bottom)
				(hide yes)
			)
		)
		(property "Description" ""
			(at 123.19 177.8 0)
			(effects
				(font
					(size 1.27 1.27)
				)
				(hide yes)
			)
		)
		(property "Manufacturer" "Bourns"
			(at 100.33 198.12 0)
			(effects
				(font
					(size 1.27 1.27)
					(thickness 0.15)
				)
				(justify left bottom)
				(hide yes)
			)
		)
		(property "MPN" "CR0402-FX-4701GLF"
			(at 102.87 198.12 0)
			(effects
				(font
					(size 1.27 1.27)
					(thickness 0.15)
				)
				(justify left bottom)
				(hide yes)
			)
		)
		(property "Val" "4k7"
			(at 124.46 182.245 90)
			(effects
				(font
					(size 1.27 1.27)
					(thickness 0.15)
				)
				(justify left)
			)
		)
		(property "License" "Apache-2.0"
			(at 97.79 198.12 0)
			(effects
				(font
					(size 1.27 1.27)
					(thickness 0.15)
				)
				(justify left bottom)
				(hide yes)
			)
		)
		(property "Author" "Antmicro"
			(at 95.25 198.12 0)
			(effects
				(font
					(size 1.27 1.27)
					(thickness 0.15)
				)
				(justify left bottom)
				(hide yes)
			)
		)
		(property "Tolerance" "1%"
			(at 113.03 198.12 0)
			(effects
				(font
					(size 1.27 1.27)
				)
				(justify left bottom)
				(hide yes)
			)
		)
		(pin "1"
		)
		(pin "2"
		)
		(instances
			(project "data-center-rdimm-ddr5-tester"
				(path ""
					(reference "R159")
					(unit 1)
				)
			)
		)
	)
	(symbol
		(lib_id "antmicropower:+3V3")
		(at 64.77 78.74 0)
		(unit 1)
		(exclude_from_sim no)
		(in_bom yes)
		(on_board yes)
		(dnp no)
		(fields_autoplaced yes)
		(property "Reference" "#PWR0270"
			(at 64.77 82.55 0)
			(effects
				(font
					(size 1.27 1.27)
				)
				(hide yes)
			)
		)
		(property "Value" "+3V3"
			(at 61.595 76.2 0)
			(effects
				(font
					(size 1.27 1.27)
					(thickness 0.15)
				)
				(justify left bottom)
			)
		)
		(property "Footprint" ""
			(at 80.01 86.36 0)
			(effects
				(font
					(size 1.27 1.27)
					(thickness 0.15)
				)
				(justify left bottom)
				(hide yes)
			)
		)
		(property "Datasheet" ""
			(at 80.01 88.9 0)
			(effects
				(font
					(size 1.27 1.27)
					(thickness 0.15)
				)
				(justify left bottom)
				(hide yes)
			)
		)
		(property "Description" ""
			(at 64.77 78.74 0)
			(effects
				(font
					(size 1.27 1.27)
				)
				(hide yes)
			)
		)
		(property "Author" "Antmicro"
			(at 80.01 81.28 0)
			(effects
				(font
					(size 1.27 1.27)
					(thickness 0.15)
				)
				(justify left bottom)
				(hide yes)
			)
		)
		(property "License" "Apache-2.0"
			(at 80.01 83.82 0)
			(effects
				(font
					(size 1.27 1.27)
					(thickness 0.15)
				)
				(justify left bottom)
				(hide yes)
			)
		)
		(pin "1"
		)
		(instances
			(project "data-center-rdimm-ddr5-tester"
				(path ""
					(reference "#PWR0270")
					(unit 1)
				)
			)
		)
	)
	(symbol
		(lib_id "antmicroResistors0402:R_4k7_0402")
		(at 68.58 85.09 270)
		(unit 1)
		(exclude_from_sim no)
		(in_bom yes)
		(on_board yes)
		(dnp no)
		(property "Reference" "R123"
			(at 69.85 86.36 90)
			(effects
				(font
					(size 1.27 1.27)
				)
				(justify left)
			)
		)
		(property "Value" "R_4k7_0402"
			(at 55.88 105.41 0)
			(effects
				(font
					(size 1.27 1.27)
					(thickness 0.15)
				)
				(justify left bottom)
				(hide yes)
			)
		)
		(property "Footprint" "antmicro-footprints:R_0402_1005Metric"
			(at 53.34 105.41 0)
			(effects
				(font
					(size 1.27 1.27)
					(thickness 0.15)
				)
				(justify left bottom)
				(hide yes)
			)
		)
		(property "Datasheet" "https://www.bourns.com/docs/product-datasheets/cr.pdf"
			(at 50.8 105.41 0)
			(effects
				(font
					(size 1.27 1.27)
					(thickness 0.15)
				)
				(justify left bottom)
				(hide yes)
			)
		)
		(property "Description" ""
			(at 68.58 85.09 0)
			(effects
				(font
					(size 1.27 1.27)
				)
				(hide yes)
			)
		)
		(property "Manufacturer" "Bourns"
			(at 45.72 105.41 0)
			(effects
				(font
					(size 1.27 1.27)
					(thickness 0.15)
				)
				(justify left bottom)
				(hide yes)
			)
		)
		(property "MPN" "CR0402-FX-4701GLF"
			(at 48.26 105.41 0)
			(effects
				(font
					(size 1.27 1.27)
					(thickness 0.15)
				)
				(justify left bottom)
				(hide yes)
			)
		)
		(property "Val" "4k7"
			(at 69.85 89.535 90)
			(effects
				(font
					(size 1.27 1.27)
					(thickness 0.15)
				)
				(justify left)
			)
		)
		(property "License" "Apache-2.0"
			(at 43.18 105.41 0)
			(effects
				(font
					(size 1.27 1.27)
					(thickness 0.15)
				)
				(justify left bottom)
				(hide yes)
			)
		)
		(property "Author" "Antmicro"
			(at 40.64 105.41 0)
			(effects
				(font
					(size 1.27 1.27)
					(thickness 0.15)
				)
				(justify left bottom)
				(hide yes)
			)
		)
		(property "Tolerance" "1%"
			(at 58.42 105.41 0)
			(effects
				(font
					(size 1.27 1.27)
				)
				(justify left bottom)
				(hide yes)
			)
		)
		(pin "1"
		)
		(pin "2"
		)
		(instances
			(project "data-center-rdimm-ddr5-tester"
				(path ""
					(reference "R123")
					(unit 1)
				)
			)
		)
	)
	(symbol
		(lib_id "antmicropower:+3V3")
		(at 214.63 50.8 0)
		(unit 1)
		(exclude_from_sim no)
		(in_bom yes)
		(on_board yes)
		(dnp no)
		(property "Reference" "#PWR0514"
			(at 229.87 50.8 0)
			(effects
				(font
					(size 1.27 1.27)
					(thickness 0.15)
				)
				(justify left bottom)
				(hide yes)
			)
		)
		(property "Value" "+3V3"
			(at 214.63 46.99 0)
			(effects
				(font
					(size 1.27 1.27)
					(thickness 0.15)
				)
			)
		)
		(property "Footprint" ""
			(at 229.87 58.42 0)
			(effects
				(font
					(size 1.27 1.27)
					(thickness 0.15)
				)
				(justify left bottom)
				(hide yes)
			)
		)
		(property "Datasheet" ""
			(at 229.87 60.96 0)
			(effects
				(font
					(size 1.27 1.27)
					(thickness 0.15)
				)
				(justify left bottom)
				(hide yes)
			)
		)
		(property "Description" ""
			(at 214.63 50.8 0)
			(effects
				(font
					(size 1.27 1.27)
				)
				(hide yes)
			)
		)
		(property "Author" "Antmicro"
			(at 229.87 53.34 0)
			(effects
				(font
					(size 1.27 1.27)
					(thickness 0.15)
				)
				(justify left bottom)
				(hide yes)
			)
		)
		(property "License" "Apache-2.0"
			(at 229.87 55.88 0)
			(effects
				(font
					(size 1.27 1.27)
					(thickness 0.15)
				)
				(justify left bottom)
				(hide yes)
			)
		)
		(pin "1"
		)
		(instances
			(project "data-center-rdimm-ddr5-tester"
				(path ""
					(reference "#PWR0514")
					(unit 1)
				)
			)
		)
	)
	(symbol
		(lib_id "antmicroTransistorsFETsMOSFETsSingle:BSS84AKW")
		(at 330.2 68.58 270)
		(mirror x)
		(unit 1)
		(exclude_from_sim no)
		(in_bom yes)
		(on_board yes)
		(dnp no)
		(property "Reference" "Q24"
			(at 332.74 54.61 90)
			(effects
				(font
					(size 1.27 1.27)
					(thickness 0.15)
				)
			)
		)
		(property "Value" "BSS84AKW"
			(at 322.58 45.72 0)
			(effects
				(font
					(size 1.27 1.27)
					(thickness 0.15)
				)
				(justify left bottom)
				(hide yes)
			)
		)
		(property "Footprint" "antmicro-footprints:SOT-323"
			(at 320.04 45.72 0)
			(effects
				(font
					(size 1.27 1.27)
					(thickness 0.15)
				)
				(justify left bottom)
				(hide yes)
			)
		)
		(property "Datasheet" "https://assets.nexperia.com/documents/data-sheet/BSS84AKW.pdf"
			(at 317.5 45.72 0)
			(effects
				(font
					(size 1.27 1.27)
					(thickness 0.15)
				)
				(justify left bottom)
				(hide yes)
			)
		)
		(property "Description" ""
			(at 330.2 68.58 0)
			(effects
				(font
					(size 1.27 1.27)
				)
				(hide yes)
			)
		)
		(property "MPN" "BSS84AKW,115"
			(at 332.74 57.15 90)
			(effects
				(font
					(size 1.27 1.27)
					(thickness 0.15)
				)
			)
		)
		(property "Manufacturer" "Nexperia"
			(at 314.96 45.72 0)
			(effects
				(font
					(size 1.27 1.27)
					(thickness 0.15)
				)
				(justify left bottom)
				(hide yes)
			)
		)
		(property "Author" "Antmicro"
			(at 312.42 45.72 0)
			(effects
				(font
					(size 1.27 1.27)
					(thickness 0.15)
				)
				(justify left bottom)
				(hide yes)
			)
		)
		(property "License" "Apache-2.0"
			(at 309.88 45.72 0)
			(effects
				(font
					(size 1.27 1.27)
					(thickness 0.15)
				)
				(justify left bottom)
				(hide yes)
			)
		)
		(pin "1"
		)
		(pin "2"
		)
		(pin "3"
		)
		(instances
			(project "data-center-rdimm-ddr5-tester"
				(path ""
					(reference "Q24")
					(unit 1)
				)
			)
		)
	)
	(symbol
		(lib_id "antmicropower:+1V8")
		(at 303.53 50.8 0)
		(unit 1)
		(exclude_from_sim no)
		(in_bom yes)
		(on_board yes)
		(dnp no)
		(property "Reference" "#PWR0521"
			(at 318.77 53.34 0)
			(effects
				(font
					(size 1.27 1.27)
					(thickness 0.15)
				)
				(justify left bottom)
				(hide yes)
			)
		)
		(property "Value" "+1V8"
			(at 303.53 46.99 0)
			(effects
				(font
					(size 1.27 1.27)
					(thickness 0.15)
				)
			)
		)
		(property "Footprint" ""
			(at 318.77 58.42 0)
			(effects
				(font
					(size 1.27 1.27)
					(thickness 0.15)
				)
				(justify left bottom)
				(hide yes)
			)
		)
		(property "Datasheet" ""
			(at 318.77 60.96 0)
			(effects
				(font
					(size 1.27 1.27)
					(thickness 0.15)
				)
				(justify left bottom)
				(hide yes)
			)
		)
		(property "Description" ""
			(at 303.53 50.8 0)
			(effects
				(font
					(size 1.27 1.27)
				)
				(hide yes)
			)
		)
		(property "Author" "Antmicro"
			(at 318.77 55.88 0)
			(effects
				(font
					(size 1.27 1.27)
					(thickness 0.15)
				)
				(justify left bottom)
				(hide yes)
			)
		)
		(property "License" "Apache-2.0"
			(at 318.77 58.42 0)
			(effects
				(font
					(size 1.27 1.27)
					(thickness 0.15)
				)
				(justify left bottom)
				(hide yes)
			)
		)
		(pin "1"
		)
		(instances
			(project "data-center-rdimm-ddr5-tester"
				(path ""
					(reference "#PWR0521")
					(unit 1)
				)
			)
		)
	)
	(symbol
		(lib_id "antmicroTVSDiodes:TPD4E05U06QDQARQ1")
		(at 353.06 105.41 0)
		(unit 1)
		(exclude_from_sim no)
		(in_bom yes)
		(on_board yes)
		(dnp no)
		(fields_autoplaced yes)
		(property "Reference" "U33"
			(at 363.22 108.585 0)
			(effects
				(font
					(size 1.27 1.27)
				)
				(justify left)
			)
		)
		(property "Value" "TPD4E05U06QDQARQ1"
			(at 355.6 118.745 0)
			(effects
				(font
					(size 1.27 1.27)
					(thickness 0.15)
				)
				(justify left)
				(hide yes)
			)
		)
		(property "Footprint" "antmicro-footprints:USON-10_2.5x1mm_P0.5mm"
			(at 377.19 110.49 0)
			(effects
				(font
					(size 1.27 1.27)
					(thickness 0.15)
				)
				(justify left bottom)
				(hide yes)
			)
		)
		(property "Datasheet" "https://www.ti.com/lit/ds/symlink/tpd4e05u06-q1.pdf?HQS=dis-mous-null-mousermode-dsf-pf-null-wwe&ts=1663591265741&ref_url=https%253A%252F%252Fwww.mouser.com%252F"
			(at 377.19 113.03 0)
			(effects
				(font
					(size 1.27 1.27)
					(thickness 0.15)
				)
				(justify left bottom)
				(hide yes)
			)
		)
		(property "Description" ""
			(at 353.06 105.41 0)
			(effects
				(font
					(size 1.27 1.27)
				)
				(hide yes)
			)
		)
		(property "Manufacturer" "Texas Instruments"
			(at 377.19 115.57 0)
			(effects
				(font
					(size 1.27 1.27)
					(thickness 0.15)
				)
				(justify left bottom)
				(hide yes)
			)
		)
		(property "MPN" "TPD4E05U06QDQARQ1"
			(at 363.22 111.125 0)
			(effects
				(font
					(size 1.27 1.27)
					(thickness 0.15)
				)
				(justify left)
			)
		)
		(property "Author" "Antmicro"
			(at 377.19 120.65 0)
			(effects
				(font
					(size 1.27 1.27)
					(thickness 0.15)
				)
				(justify left bottom)
				(hide yes)
			)
		)
		(property "License" "Apache-2.0"
			(at 377.19 123.19 0)
			(effects
				(font
					(size 1.27 1.27)
					(thickness 0.15)
				)
				(justify left bottom)
				(hide yes)
			)
		)
		(pin "1"
		)
		(pin "10"
		)
		(pin "2"
		)
		(pin "3"
		)
		(pin "4"
		)
		(pin "5"
		)
		(pin "6"
		)
		(pin "7"
		)
		(pin "8"
		)
		(pin "9"
		)
		(instances
			(project "data-center-rdimm-ddr5-tester"
				(path ""
					(reference "U33")
					(unit 1)
				)
			)
		)
	)
	(symbol
		(lib_id "antmicropower:+1V8")
		(at 129.54 50.8 0)
		(mirror y)
		(unit 1)
		(exclude_from_sim no)
		(in_bom yes)
		(on_board yes)
		(dnp no)
		(fields_autoplaced yes)
		(property "Reference" "#PWR0273"
			(at 114.3 53.34 0)
			(effects
				(font
					(size 1.27 1.27)
					(thickness 0.15)
				)
				(justify left bottom)
				(hide yes)
			)
		)
		(property "Value" "+1V8"
			(at 132.715 48.26 0)
			(effects
				(font
					(size 1.27 1.27)
					(thickness 0.15)
				)
				(justify left bottom)
			)
		)
		(property "Footprint" ""
			(at 114.3 58.42 0)
			(effects
				(font
					(size 1.27 1.27)
					(thickness 0.15)
				)
				(justify left bottom)
				(hide yes)
			)
		)
		(property "Datasheet" ""
			(at 114.3 60.96 0)
			(effects
				(font
					(size 1.27 1.27)
					(thickness 0.15)
				)
				(justify left bottom)
				(hide yes)
			)
		)
		(property "Description" ""
			(at 129.54 50.8 0)
			(effects
				(font
					(size 1.27 1.27)
				)
				(hide yes)
			)
		)
		(property "Author" "Antmicro"
			(at 114.3 55.88 0)
			(effects
				(font
					(size 1.27 1.27)
					(thickness 0.15)
				)
				(justify left bottom)
				(hide yes)
			)
		)
		(property "License" "Apache-2.0"
			(at 114.3 58.42 0)
			(effects
				(font
					(size 1.27 1.27)
					(thickness 0.15)
				)
				(justify left bottom)
				(hide yes)
			)
		)
		(pin "1"
		)
		(instances
			(project "data-center-rdimm-ddr5-tester"
				(path ""
					(reference "#PWR0273")
					(unit 1)
				)
			)
		)
	)
	(symbol
		(lib_id "antmicropower:GND")
		(at 99.06 101.6 0)
		(unit 1)
		(exclude_from_sim no)
		(in_bom yes)
		(on_board yes)
		(dnp no)
		(fields_autoplaced yes)
		(property "Reference" "#PWR0271"
			(at 99.06 107.95 0)
			(effects
				(font
					(size 1.27 1.27)
				)
				(hide yes)
			)
		)
		(property "Value" "GND"
			(at 97.155 106.045 0)
			(effects
				(font
					(size 1.27 1.27)
					(thickness 0.15)
				)
				(justify left bottom)
			)
		)
		(property "Footprint" ""
			(at 107.95 109.22 0)
			(effects
				(font
					(size 1.27 1.27)
					(thickness 0.15)
				)
				(justify left bottom)
				(hide yes)
			)
		)
		(property "Datasheet" ""
			(at 107.95 114.3 0)
			(effects
				(font
					(size 1.27 1.27)
					(thickness 0.15)
				)
				(justify left bottom)
				(hide yes)
			)
		)
		(property "Description" ""
			(at 99.06 101.6 0)
			(effects
				(font
					(size 1.27 1.27)
				)
				(hide yes)
			)
		)
		(property "Author" "Antmicro"
			(at 107.95 106.68 0)
			(effects
				(font
					(size 1.27 1.27)
					(thickness 0.15)
				)
				(justify left bottom)
				(hide yes)
			)
		)
		(property "License" "Apache-2.0"
			(at 107.95 109.22 0)
			(effects
				(font
					(size 1.27 1.27)
					(thickness 0.15)
				)
				(justify left bottom)
				(hide yes)
			)
		)
		(pin "1"
		)
		(instances
			(project "data-center-rdimm-ddr5-tester"
				(path ""
					(reference "#PWR0271")
					(unit 1)
				)
			)
		)
	)
	(symbol
		(lib_id "antmicropower:GND")
		(at 356.87 68.58 0)
		(mirror y)
		(unit 1)
		(exclude_from_sim no)
		(in_bom yes)
		(on_board yes)
		(dnp no)
		(fields_autoplaced yes)
		(property "Reference" "#PWR0527"
			(at 356.87 74.93 0)
			(effects
				(font
					(size 1.27 1.27)
				)
				(hide yes)
			)
		)
		(property "Value" "GND"
			(at 358.775 73.025 0)
			(effects
				(font
					(size 1.27 1.27)
					(thickness 0.15)
				)
				(justify left bottom)
			)
		)
		(property "Footprint" ""
			(at 347.98 76.2 0)
			(effects
				(font
					(size 1.27 1.27)
					(thickness 0.15)
				)
				(justify left bottom)
				(hide yes)
			)
		)
		(property "Datasheet" ""
			(at 347.98 81.28 0)
			(effects
				(font
					(size 1.27 1.27)
					(thickness 0.15)
				)
				(justify left bottom)
				(hide yes)
			)
		)
		(property "Description" ""
			(at 356.87 68.58 0)
			(effects
				(font
					(size 1.27 1.27)
				)
				(hide yes)
			)
		)
		(property "Author" "Antmicro"
			(at 347.98 73.66 0)
			(effects
				(font
					(size 1.27 1.27)
					(thickness 0.15)
				)
				(justify left bottom)
				(hide yes)
			)
		)
		(property "License" "Apache-2.0"
			(at 347.98 76.2 0)
			(effects
				(font
					(size 1.27 1.27)
					(thickness 0.15)
				)
				(justify left bottom)
				(hide yes)
			)
		)
		(pin "1"
		)
		(instances
			(project "data-center-rdimm-ddr5-tester"
				(path ""
					(reference "#PWR0527")
					(unit 1)
				)
			)
		)
	)
	(symbol
		(lib_id "antmicroInterfaceAnalogSwitchesMultiplexersDemultiplexers:TS5A3359_VSSOP")
		(at 143.51 186.69 0)
		(unit 1)
		(exclude_from_sim no)
		(in_bom yes)
		(on_board yes)
		(dnp no)
		(fields_autoplaced yes)
		(property "Reference" "U23"
			(at 156.845 179.07 0)
			(effects
				(font
					(size 1.27 1.27)
					(thickness 0.15)
				)
			)
		)
		(property "Value" "TS5A3359_VSSOP"
			(at 185.42 191.77 0)
			(effects
				(font
					(size 1.27 1.27)
					(thickness 0.15)
				)
				(justify left bottom)
				(hide yes)
			)
		)
		(property "Footprint" "antmicro-footprints:VSSOP-8_2.3x2mm_P0.5mm"
			(at 185.42 194.31 0)
			(effects
				(font
					(size 1.27 1.27)
					(thickness 0.15)
				)
				(justify left bottom)
				(hide yes)
			)
		)
		(property "Datasheet" "https://www.ti.com/general/docs/suppproductinfo.tsp?distId=26&gotoUrl=http%3A%2F%2Fwww.ti.com%2Flit%2Fgpn%2Fts5a3359"
			(at 185.42 196.85 0)
			(effects
				(font
					(size 1.27 1.27)
					(thickness 0.15)
				)
				(justify left bottom)
				(hide yes)
			)
		)
		(property "Description" ""
			(at 143.51 186.69 0)
			(effects
				(font
					(size 1.27 1.27)
				)
				(hide yes)
			)
		)
		(property "MPN" "TS5A3359DCUR"
			(at 156.845 181.61 0)
			(effects
				(font
					(size 1.27 1.27)
					(thickness 0.15)
				)
			)
		)
		(property "Manufacturer" "Texas Instruments"
			(at 185.42 201.93 0)
			(effects
				(font
					(size 1.27 1.27)
					(thickness 0.15)
				)
				(justify left bottom)
				(hide yes)
			)
		)
		(property "Author" "Antmicro"
			(at 185.42 204.47 0)
			(effects
				(font
					(size 1.27 1.27)
					(thickness 0.15)
				)
				(justify left bottom)
				(hide yes)
			)
		)
		(property "License" "Apache-2.0"
			(at 185.42 207.01 0)
			(effects
				(font
					(size 1.27 1.27)
					(thickness 0.15)
				)
				(justify left bottom)
				(hide yes)
			)
		)
		(pin "2"
		)
		(pin "6"
		)
		(pin "7"
		)
		(pin "5"
		)
		(pin "8"
		)
		(pin "4"
		)
		(pin "1"
		)
		(pin "3"
		)
		(instances
			(project "data-center-rdimm-ddr5-tester"
				(path ""
					(reference "U23")
					(unit 1)
				)
			)
		)
	)
)
